FILE_TYPE = MACRO_DRAWING;
SET COLOR_WIRE YELLOW;
SET COLOR_PROP ORANGE;
SET COLOR_DOT WHITE;
SET COLOR_ARC YELLOW;
SET COLOR_BODY GREEN;
SET COLOR_NOTE PURPLE;
SET PROP_DISPLAY VALUE;
SET PAGE_NUMBER P23;
FORCEADD GENOA_SP5..13
(-4775 5075);
FORCEPROP 1 LAST LOCATION U25
J 0
(-5870 6331);
DISPLAY 0.489362 (-5870 6331);
PAINT SKYBLUE (-5870 6331);
FORCEPROP 0 LAST $SEC 13
J 0
(-5850 6375);
DISPLAY 0.680851 (-5850 6375);
PAINT MONO (-5850 6375);
DISPLAY INVISIBLE (-5850 6375);
FORCEPROP 0 LAST CDS_SEC 13
J 0
(-5875 6275);
DISPLAY 1.021277 (-5875 6275);
DISPLAY INVISIBLE (-5875 6275);
FORCEPROP 0 LASTPIN (-6025 5775) $PN AE23
J 2
(-6035 5785);
DISPLAY 0.489362 (-6035 5785);
PAINT MONO (-6035 5785);
FORCEPROP 0 LASTPIN (-6025 5675) $PN AC23
J 2
(-6035 5685);
DISPLAY 0.489362 (-6035 5685);
PAINT MONO (-6035 5685);
FORCEPROP 0 LASTPIN (-6025 5575) $PN AG23
J 2
(-6035 5585);
DISPLAY 0.489362 (-6035 5585);
PAINT MONO (-6035 5585);
FORCEPROP 0 LASTPIN (-6025 5475) $PN AE26
J 2
(-6035 5485);
DISPLAY 0.489362 (-6035 5485);
PAINT MONO (-6035 5485);
FORCEPROP 0 LASTPIN (-6025 5375) $PN AC26
J 2
(-6035 5385);
DISPLAY 0.489362 (-6035 5385);
PAINT MONO (-6035 5385);
FORCEPROP 0 LASTPIN (-6025 5275) $PN AG26
J 2
(-6035 5285);
DISPLAY 0.489362 (-6035 5285);
PAINT MONO (-6035 5285);
FORCEPROP 0 LASTPIN (-6025 5175) $PN AE29
J 2
(-6035 5185);
DISPLAY 0.489362 (-6035 5185);
PAINT MONO (-6035 5185);
FORCEPROP 0 LASTPIN (-6025 5075) $PN AC29
J 2
(-6035 5085);
DISPLAY 0.489362 (-6035 5085);
PAINT MONO (-6035 5085);
FORCEPROP 0 LASTPIN (-6025 4975) $PN AG29
J 2
(-6035 4985);
DISPLAY 0.489362 (-6035 4985);
PAINT MONO (-6035 4985);
FORCEPROP 0 LASTPIN (-6025 4875) $PN AE32
J 2
(-6035 4885);
DISPLAY 0.489362 (-6035 4885);
PAINT MONO (-6035 4885);
FORCEPROP 0 LASTPIN (-6025 4775) $PN AC32
J 2
(-6035 4785);
DISPLAY 0.489362 (-6035 4785);
PAINT MONO (-6035 4785);
FORCEPROP 0 LASTPIN (-6025 4675) $PN AA32
J 2
(-6035 4685);
DISPLAY 0.489362 (-6035 4685);
PAINT MONO (-6035 4685);
FORCEPROP 0 LASTPIN (-6025 4575) $PN AG32
J 2
(-6035 4585);
DISPLAY 0.489362 (-6035 4585);
PAINT MONO (-6035 4585);
FORCEPROP 0 LASTPIN (-6025 4475) $PN AB35
J 2
(-6035 4485);
DISPLAY 0.489362 (-6035 4485);
PAINT MONO (-6035 4485);
FORCEPROP 0 LASTPIN (-6025 4375) $PN AD35
J 2
(-6035 4385);
DISPLAY 0.489362 (-6035 4385);
PAINT MONO (-6035 4385);
FORCEPROP 0 LASTPIN (-6025 4275) $PN AF35
J 2
(-6035 4285);
DISPLAY 0.489362 (-6035 4285);
PAINT MONO (-6035 4285);
FORCEPROP 0 LASTPIN (-6025 5825) $PN AE24
J 2
(-6035 5835);
DISPLAY 0.489362 (-6035 5835);
PAINT MONO (-6035 5835);
FORCEPROP 0 LASTPIN (-6025 5725) $PN AC24
J 2
(-6035 5735);
DISPLAY 0.489362 (-6035 5735);
PAINT MONO (-6035 5735);
FORCEPROP 0 LASTPIN (-6025 5625) $PN AG24
J 2
(-6035 5635);
DISPLAY 0.489362 (-6035 5635);
PAINT MONO (-6035 5635);
FORCEPROP 0 LASTPIN (-6025 5525) $PN AE27
J 2
(-6035 5535);
DISPLAY 0.489362 (-6035 5535);
PAINT MONO (-6035 5535);
FORCEPROP 0 LASTPIN (-6025 5425) $PN AC27
J 2
(-6035 5435);
DISPLAY 0.489362 (-6035 5435);
PAINT MONO (-6035 5435);
FORCEPROP 0 LASTPIN (-6025 5325) $PN AG27
J 2
(-6035 5335);
DISPLAY 0.489362 (-6035 5335);
PAINT MONO (-6035 5335);
FORCEPROP 0 LASTPIN (-6025 5225) $PN AE30
J 2
(-6035 5235);
DISPLAY 0.489362 (-6035 5235);
PAINT MONO (-6035 5235);
FORCEPROP 0 LASTPIN (-6025 5125) $PN AC30
J 2
(-6035 5135);
DISPLAY 0.489362 (-6035 5135);
PAINT MONO (-6035 5135);
FORCEPROP 0 LASTPIN (-6025 5025) $PN AG30
J 2
(-6035 5035);
DISPLAY 0.489362 (-6035 5035);
PAINT MONO (-6035 5035);
FORCEPROP 0 LASTPIN (-6025 4925) $PN AE33
J 2
(-6035 4935);
DISPLAY 0.489362 (-6035 4935);
PAINT MONO (-6035 4935);
FORCEPROP 0 LASTPIN (-6025 4825) $PN AC33
J 2
(-6035 4835);
DISPLAY 0.489362 (-6035 4835);
PAINT MONO (-6035 4835);
FORCEPROP 0 LASTPIN (-6025 4725) $PN AA33
J 2
(-6035 4735);
DISPLAY 0.489362 (-6035 4735);
PAINT MONO (-6035 4735);
FORCEPROP 0 LASTPIN (-6025 4625) $PN AG33
J 2
(-6035 4635);
DISPLAY 0.489362 (-6035 4635);
PAINT MONO (-6035 4635);
FORCEPROP 0 LASTPIN (-6025 4525) $PN AB36
J 2
(-6035 4535);
DISPLAY 0.489362 (-6035 4535);
PAINT MONO (-6035 4535);
FORCEPROP 0 LASTPIN (-6025 4425) $PN AD36
J 2
(-6035 4435);
DISPLAY 0.489362 (-6035 4435);
PAINT MONO (-6035 4435);
FORCEPROP 0 LASTPIN (-6025 4325) $PN AF36
J 2
(-6035 4335);
DISPLAY 0.489362 (-6035 4335);
PAINT MONO (-6035 4335);
FORCEPROP 0 LASTPIN (-3525 5775) $PN N24
J 0
(-3515 5785);
DISPLAY 0.489362 (-3515 5785);
PAINT MONO (-3515 5785);
FORCEPROP 0 LASTPIN (-3525 5675) $PN J24
J 0
(-3515 5685);
DISPLAY 0.489362 (-3515 5685);
PAINT MONO (-3515 5685);
FORCEPROP 0 LASTPIN (-3525 5575) $PN G24
J 0
(-3515 5585);
DISPLAY 0.489362 (-3515 5585);
PAINT MONO (-3515 5585);
FORCEPROP 0 LASTPIN (-3525 5475) $PN L24
J 0
(-3515 5485);
DISPLAY 0.489362 (-3515 5485);
PAINT MONO (-3515 5485);
FORCEPROP 0 LASTPIN (-3525 5375) $PN J27
J 0
(-3515 5385);
DISPLAY 0.489362 (-3515 5385);
PAINT MONO (-3515 5385);
FORCEPROP 0 LASTPIN (-3525 5275) $PN G27
J 0
(-3515 5285);
DISPLAY 0.489362 (-3515 5285);
PAINT MONO (-3515 5285);
FORCEPROP 0 LASTPIN (-3525 5175) $PN L27
J 0
(-3515 5185);
DISPLAY 0.489362 (-3515 5185);
PAINT MONO (-3515 5185);
FORCEPROP 0 LASTPIN (-3525 5075) $PN J30
J 0
(-3515 5085);
DISPLAY 0.489362 (-3515 5085);
PAINT MONO (-3515 5085);
FORCEPROP 0 LASTPIN (-3525 4975) $PN G30
J 0
(-3515 4985);
DISPLAY 0.489362 (-3515 4985);
PAINT MONO (-3515 4985);
FORCEPROP 0 LASTPIN (-3525 4875) $PN L30
J 0
(-3515 4885);
DISPLAY 0.489362 (-3515 4885);
PAINT MONO (-3515 4885);
FORCEPROP 0 LASTPIN (-3525 4775) $PN J33
J 0
(-3515 4785);
DISPLAY 0.489362 (-3515 4785);
PAINT MONO (-3515 4785);
FORCEPROP 0 LASTPIN (-3525 4675) $PN G33
J 0
(-3515 4685);
DISPLAY 0.489362 (-3515 4685);
PAINT MONO (-3515 4685);
FORCEPROP 0 LASTPIN (-3525 4575) $PN L33
J 0
(-3515 4585);
DISPLAY 0.489362 (-3515 4585);
PAINT MONO (-3515 4585);
FORCEPROP 0 LASTPIN (-3525 4475) $PN H36
J 0
(-3515 4485);
DISPLAY 0.489362 (-3515 4485);
PAINT MONO (-3515 4485);
FORCEPROP 0 LASTPIN (-3525 4375) $PN K36
J 0
(-3515 4385);
DISPLAY 0.489362 (-3515 4385);
PAINT MONO (-3515 4385);
FORCEPROP 0 LASTPIN (-3525 4275) $PN M36
J 0
(-3515 4285);
DISPLAY 0.489362 (-3515 4285);
PAINT MONO (-3515 4285);
FORCEPROP 0 LASTPIN (-3525 5825) $PN N23
J 0
(-3515 5835);
DISPLAY 0.489362 (-3515 5835);
PAINT MONO (-3515 5835);
FORCEPROP 0 LASTPIN (-3525 5725) $PN J23
J 0
(-3515 5735);
DISPLAY 0.489362 (-3515 5735);
PAINT MONO (-3515 5735);
FORCEPROP 0 LASTPIN (-3525 5625) $PN G23
J 0
(-3515 5635);
DISPLAY 0.489362 (-3515 5635);
PAINT MONO (-3515 5635);
FORCEPROP 0 LASTPIN (-3525 5525) $PN L23
J 0
(-3515 5535);
DISPLAY 0.489362 (-3515 5535);
PAINT MONO (-3515 5535);
FORCEPROP 0 LASTPIN (-3525 5425) $PN J26
J 0
(-3515 5435);
DISPLAY 0.489362 (-3515 5435);
PAINT MONO (-3515 5435);
FORCEPROP 0 LASTPIN (-3525 5325) $PN G26
J 0
(-3515 5335);
DISPLAY 0.489362 (-3515 5335);
PAINT MONO (-3515 5335);
FORCEPROP 0 LASTPIN (-3525 5225) $PN L26
J 0
(-3515 5235);
DISPLAY 0.489362 (-3515 5235);
PAINT MONO (-3515 5235);
FORCEPROP 0 LASTPIN (-3525 5125) $PN J29
J 0
(-3515 5135);
DISPLAY 0.489362 (-3515 5135);
PAINT MONO (-3515 5135);
FORCEPROP 0 LASTPIN (-3525 5025) $PN G29
J 0
(-3515 5035);
DISPLAY 0.489362 (-3515 5035);
PAINT MONO (-3515 5035);
FORCEPROP 0 LASTPIN (-3525 4925) $PN L29
J 0
(-3515 4935);
DISPLAY 0.489362 (-3515 4935);
PAINT MONO (-3515 4935);
FORCEPROP 0 LASTPIN (-3525 4825) $PN J32
J 0
(-3515 4835);
DISPLAY 0.489362 (-3515 4835);
PAINT MONO (-3515 4835);
FORCEPROP 0 LASTPIN (-3525 4725) $PN G32
J 0
(-3515 4735);
DISPLAY 0.489362 (-3515 4735);
PAINT MONO (-3515 4735);
FORCEPROP 0 LASTPIN (-3525 4625) $PN L32
J 0
(-3515 4635);
DISPLAY 0.489362 (-3515 4635);
PAINT MONO (-3515 4635);
FORCEPROP 0 LASTPIN (-3525 4525) $PN H35
J 0
(-3515 4535);
DISPLAY 0.489362 (-3515 4535);
PAINT MONO (-3515 4535);
FORCEPROP 0 LASTPIN (-3525 4425) $PN K35
J 0
(-3515 4435);
DISPLAY 0.489362 (-3515 4435);
PAINT MONO (-3515 4435);
FORCEPROP 0 LASTPIN (-3525 4325) $PN M35
J 0
(-3515 4335);
DISPLAY 0.489362 (-3515 4335);
PAINT MONO (-3515 4335);
FORCEPROP 2 LAST PART_TYPE SMLF
J 0
(-5875 6225);
DISPLAY 1.021277 (-5875 6225);
FORCEPROP 2 LAST VALUE SOCKET6096_13568-001
J 0
(-5875 6125);
DISPLAY 0.489362 (-5875 6125);
PAINT SKYBLUE (-5875 6125);
FORCEPROP 1 LAST PART_NUMBER DGA^6000030
J 0
(-5870 6184);
DISPLAY 0.489362 (-5870 6184);
PAINT SKYBLUE (-5870 6184);
FORCEPROP 1 LAST MATERIAL IO
J 0
(-5870 6057);
DISPLAY 0.489362 (-5870 6057);
PAINT SKYBLUE (-5870 6057);
FORCEPROP 2 LAST CDS_LIB pure_quanta
J 0
(-4775 5075);
DISPLAY INVISIBLE (-4775 5075);
FORCEPROP 1 LAST NEEDS_NO_SIZE TRUE
J 0
(-4775 5075);
DISPLAY 0.723404 (-4775 5075);
PAINT GREEN (-4775 5075);
DISPLAY INVISIBLE (-4775 5075);
FORCEPROP 1 LAST CDS_LMAN_SYM_OUTLINE -1100,950,1100,-950
J 0
(-4775 5075);
DISPLAY 0.468085 (-4775 5075);
PAINT GREEN (-4775 5075);
DISPLAY INVISIBLE (-4775 5075);
FORCEPROP 1 LAST PATH I215
J 0
(-4775 5075);
DISPLAY 0.723404 (-4775 5075);
PAINT GREEN (-4775 5075);
DISPLAY INVISIBLE (-4775 5075);
FORCEADD GENOA_SP5..14
(-4750 2200);
FORCEPROP 1 LAST LOCATION U25
J 0
(-5845 3456);
DISPLAY 0.489362 (-5845 3456);
PAINT SKYBLUE (-5845 3456);
FORCEPROP 0 LAST $SEC 14
J 0
(-5825 3500);
DISPLAY 0.680851 (-5825 3500);
PAINT MONO (-5825 3500);
DISPLAY INVISIBLE (-5825 3500);
FORCEPROP 0 LAST CDS_SEC 14
J 0
(-5850 3400);
DISPLAY 1.021277 (-5850 3400);
DISPLAY INVISIBLE (-5850 3400);
FORCEPROP 0 LASTPIN (-6000 2900) $PN AL23
J 2
(-6010 2910);
DISPLAY 0.489362 (-6010 2910);
PAINT MONO (-6010 2910);
FORCEPROP 0 LASTPIN (-6000 2800) $PN AJ23
J 2
(-6010 2810);
DISPLAY 0.489362 (-6010 2810);
PAINT MONO (-6010 2810);
FORCEPROP 0 LASTPIN (-6000 2700) $PN AN23
J 2
(-6010 2710);
DISPLAY 0.489362 (-6010 2710);
PAINT MONO (-6010 2710);
FORCEPROP 0 LASTPIN (-6000 2600) $PN AL26
J 2
(-6010 2610);
DISPLAY 0.489362 (-6010 2610);
PAINT MONO (-6010 2610);
FORCEPROP 0 LASTPIN (-6000 2500) $PN AJ26
J 2
(-6010 2510);
DISPLAY 0.489362 (-6010 2510);
PAINT MONO (-6010 2510);
FORCEPROP 0 LASTPIN (-6000 2400) $PN AN26
J 2
(-6010 2410);
DISPLAY 0.489362 (-6010 2410);
PAINT MONO (-6010 2410);
FORCEPROP 0 LASTPIN (-6000 2300) $PN AL29
J 2
(-6010 2310);
DISPLAY 0.489362 (-6010 2310);
PAINT MONO (-6010 2310);
FORCEPROP 0 LASTPIN (-6000 2200) $PN AJ29
J 2
(-6010 2210);
DISPLAY 0.489362 (-6010 2210);
PAINT MONO (-6010 2210);
FORCEPROP 0 LASTPIN (-6000 2100) $PN AN29
J 2
(-6010 2110);
DISPLAY 0.489362 (-6010 2110);
PAINT MONO (-6010 2110);
FORCEPROP 0 LASTPIN (-6000 2000) $PN AL32
J 2
(-6010 2010);
DISPLAY 0.489362 (-6010 2010);
PAINT MONO (-6010 2010);
FORCEPROP 0 LASTPIN (-6000 1900) $PN AJ32
J 2
(-6010 1910);
DISPLAY 0.489362 (-6010 1910);
PAINT MONO (-6010 1910);
FORCEPROP 0 LASTPIN (-6000 1800) $PN AN32
J 2
(-6010 1810);
DISPLAY 0.489362 (-6010 1810);
PAINT MONO (-6010 1810);
FORCEPROP 0 LASTPIN (-6000 1700) $PN AK35
J 2
(-6010 1710);
DISPLAY 0.489362 (-6010 1710);
PAINT MONO (-6010 1710);
FORCEPROP 0 LASTPIN (-6000 1600) $PN AH35
J 2
(-6010 1610);
DISPLAY 0.489362 (-6010 1610);
PAINT MONO (-6010 1610);
FORCEPROP 0 LASTPIN (-6000 1500) $PN AM35
J 2
(-6010 1510);
DISPLAY 0.489362 (-6010 1510);
PAINT MONO (-6010 1510);
FORCEPROP 0 LASTPIN (-6000 1400) $PN AP35
J 2
(-6010 1410);
DISPLAY 0.489362 (-6010 1410);
PAINT MONO (-6010 1410);
FORCEPROP 0 LASTPIN (-6000 2950) $PN AL24
J 2
(-6010 2960);
DISPLAY 0.489362 (-6010 2960);
PAINT MONO (-6010 2960);
FORCEPROP 0 LASTPIN (-6000 2850) $PN AJ24
J 2
(-6010 2860);
DISPLAY 0.489362 (-6010 2860);
PAINT MONO (-6010 2860);
FORCEPROP 0 LASTPIN (-6000 2750) $PN AN24
J 2
(-6010 2760);
DISPLAY 0.489362 (-6010 2760);
PAINT MONO (-6010 2760);
FORCEPROP 0 LASTPIN (-6000 2650) $PN AL27
J 2
(-6010 2660);
DISPLAY 0.489362 (-6010 2660);
PAINT MONO (-6010 2660);
FORCEPROP 0 LASTPIN (-6000 2550) $PN AJ27
J 2
(-6010 2560);
DISPLAY 0.489362 (-6010 2560);
PAINT MONO (-6010 2560);
FORCEPROP 0 LASTPIN (-6000 2450) $PN AN27
J 2
(-6010 2460);
DISPLAY 0.489362 (-6010 2460);
PAINT MONO (-6010 2460);
FORCEPROP 0 LASTPIN (-6000 2350) $PN AL30
J 2
(-6010 2360);
DISPLAY 0.489362 (-6010 2360);
PAINT MONO (-6010 2360);
FORCEPROP 0 LASTPIN (-6000 2250) $PN AJ30
J 2
(-6010 2260);
DISPLAY 0.489362 (-6010 2260);
PAINT MONO (-6010 2260);
FORCEPROP 0 LASTPIN (-6000 2150) $PN AN30
J 2
(-6010 2160);
DISPLAY 0.489362 (-6010 2160);
PAINT MONO (-6010 2160);
FORCEPROP 0 LASTPIN (-6000 2050) $PN AL33
J 2
(-6010 2060);
DISPLAY 0.489362 (-6010 2060);
PAINT MONO (-6010 2060);
FORCEPROP 0 LASTPIN (-6000 1950) $PN AJ33
J 2
(-6010 1960);
DISPLAY 0.489362 (-6010 1960);
PAINT MONO (-6010 1960);
FORCEPROP 0 LASTPIN (-6000 1850) $PN AN33
J 2
(-6010 1860);
DISPLAY 0.489362 (-6010 1860);
PAINT MONO (-6010 1860);
FORCEPROP 0 LASTPIN (-6000 1750) $PN AK36
J 2
(-6010 1760);
DISPLAY 0.489362 (-6010 1760);
PAINT MONO (-6010 1760);
FORCEPROP 0 LASTPIN (-6000 1650) $PN AH36
J 2
(-6010 1660);
DISPLAY 0.489362 (-6010 1660);
PAINT MONO (-6010 1660);
FORCEPROP 0 LASTPIN (-6000 1550) $PN AM36
J 2
(-6010 1560);
DISPLAY 0.489362 (-6010 1560);
PAINT MONO (-6010 1560);
FORCEPROP 0 LASTPIN (-6000 1450) $PN AP36
J 2
(-6010 1460);
DISPLAY 0.489362 (-6010 1460);
PAINT MONO (-6010 1460);
FORCEPROP 0 LASTPIN (-3500 2900) $PN U24
J 0
(-3490 2910);
DISPLAY 0.489362 (-3490 2910);
PAINT MONO (-3490 2910);
FORCEPROP 0 LASTPIN (-3500 2800) $PN R24
J 0
(-3490 2810);
DISPLAY 0.489362 (-3490 2810);
PAINT MONO (-3490 2810);
FORCEPROP 0 LASTPIN (-3500 2700) $PN W24
J 0
(-3490 2710);
DISPLAY 0.489362 (-3490 2710);
PAINT MONO (-3490 2710);
FORCEPROP 0 LASTPIN (-3500 2600) $PN U27
J 0
(-3490 2610);
DISPLAY 0.489362 (-3490 2610);
PAINT MONO (-3490 2610);
FORCEPROP 0 LASTPIN (-3500 2500) $PN R27
J 0
(-3490 2510);
DISPLAY 0.489362 (-3490 2510);
PAINT MONO (-3490 2510);
FORCEPROP 0 LASTPIN (-3500 2400) $PN N27
J 0
(-3490 2410);
DISPLAY 0.489362 (-3490 2410);
PAINT MONO (-3490 2410);
FORCEPROP 0 LASTPIN (-3500 2300) $PN W27
J 0
(-3490 2310);
DISPLAY 0.489362 (-3490 2310);
PAINT MONO (-3490 2310);
FORCEPROP 0 LASTPIN (-3500 2200) $PN R30
J 0
(-3490 2210);
DISPLAY 0.489362 (-3490 2210);
PAINT MONO (-3490 2210);
FORCEPROP 0 LASTPIN (-3500 2100) $PN N30
J 0
(-3490 2110);
DISPLAY 0.489362 (-3490 2110);
PAINT MONO (-3490 2110);
FORCEPROP 0 LASTPIN (-3500 2000) $PN U30
J 0
(-3490 2010);
DISPLAY 0.489362 (-3490 2010);
PAINT MONO (-3490 2010);
FORCEPROP 0 LASTPIN (-3500 1900) $PN R33
J 0
(-3490 1910);
DISPLAY 0.489362 (-3490 1910);
PAINT MONO (-3490 1910);
FORCEPROP 0 LASTPIN (-3500 1800) $PN N33
J 0
(-3490 1810);
DISPLAY 0.489362 (-3490 1810);
PAINT MONO (-3490 1810);
FORCEPROP 0 LASTPIN (-3500 1700) $PN U33
J 0
(-3490 1710);
DISPLAY 0.489362 (-3490 1710);
PAINT MONO (-3490 1710);
FORCEPROP 0 LASTPIN (-3500 1600) $PN P36
J 0
(-3490 1610);
DISPLAY 0.489362 (-3490 1610);
PAINT MONO (-3490 1610);
FORCEPROP 0 LASTPIN (-3500 1500) $PN T36
J 0
(-3490 1510);
DISPLAY 0.489362 (-3490 1510);
PAINT MONO (-3490 1510);
FORCEPROP 0 LASTPIN (-3500 1400) $PN V36
J 0
(-3490 1410);
DISPLAY 0.489362 (-3490 1410);
PAINT MONO (-3490 1410);
FORCEPROP 0 LASTPIN (-3500 2950) $PN U23
J 0
(-3490 2960);
DISPLAY 0.489362 (-3490 2960);
PAINT MONO (-3490 2960);
FORCEPROP 0 LASTPIN (-3500 2850) $PN R23
J 0
(-3490 2860);
DISPLAY 0.489362 (-3490 2860);
PAINT MONO (-3490 2860);
FORCEPROP 0 LASTPIN (-3500 2750) $PN W23
J 0
(-3490 2760);
DISPLAY 0.489362 (-3490 2760);
PAINT MONO (-3490 2760);
FORCEPROP 0 LASTPIN (-3500 2650) $PN U26
J 0
(-3490 2660);
DISPLAY 0.489362 (-3490 2660);
PAINT MONO (-3490 2660);
FORCEPROP 0 LASTPIN (-3500 2550) $PN R26
J 0
(-3490 2560);
DISPLAY 0.489362 (-3490 2560);
PAINT MONO (-3490 2560);
FORCEPROP 0 LASTPIN (-3500 2450) $PN N26
J 0
(-3490 2460);
DISPLAY 0.489362 (-3490 2460);
PAINT MONO (-3490 2460);
FORCEPROP 0 LASTPIN (-3500 2350) $PN W26
J 0
(-3490 2360);
DISPLAY 0.489362 (-3490 2360);
PAINT MONO (-3490 2360);
FORCEPROP 0 LASTPIN (-3500 2250) $PN R29
J 0
(-3490 2260);
DISPLAY 0.489362 (-3490 2260);
PAINT MONO (-3490 2260);
FORCEPROP 0 LASTPIN (-3500 2150) $PN N29
J 0
(-3490 2160);
DISPLAY 0.489362 (-3490 2160);
PAINT MONO (-3490 2160);
FORCEPROP 0 LASTPIN (-3500 2050) $PN U29
J 0
(-3490 2060);
DISPLAY 0.489362 (-3490 2060);
PAINT MONO (-3490 2060);
FORCEPROP 0 LASTPIN (-3500 1950) $PN R32
J 0
(-3490 1960);
DISPLAY 0.489362 (-3490 1960);
PAINT MONO (-3490 1960);
FORCEPROP 0 LASTPIN (-3500 1850) $PN N32
J 0
(-3490 1860);
DISPLAY 0.489362 (-3490 1860);
PAINT MONO (-3490 1860);
FORCEPROP 0 LASTPIN (-3500 1750) $PN U32
J 0
(-3490 1760);
DISPLAY 0.489362 (-3490 1760);
PAINT MONO (-3490 1760);
FORCEPROP 0 LASTPIN (-3500 1650) $PN P35
J 0
(-3490 1660);
DISPLAY 0.489362 (-3490 1660);
PAINT MONO (-3490 1660);
FORCEPROP 0 LASTPIN (-3500 1550) $PN T35
J 0
(-3490 1560);
DISPLAY 0.489362 (-3490 1560);
PAINT MONO (-3490 1560);
FORCEPROP 0 LASTPIN (-3500 1450) $PN V35
J 0
(-3490 1460);
DISPLAY 0.489362 (-3490 1460);
PAINT MONO (-3490 1460);
FORCEPROP 2 LAST PART_TYPE SMLF
J 0
(-5850 3350);
DISPLAY 1.021277 (-5850 3350);
FORCEPROP 1 LAST MATERIAL IO
J 0
(-5845 3182);
DISPLAY 0.489362 (-5845 3182);
PAINT SKYBLUE (-5845 3182);
FORCEPROP 2 LAST VALUE SOCKET6096_13568-001
J 0
(-5850 3250);
DISPLAY 0.489362 (-5850 3250);
PAINT SKYBLUE (-5850 3250);
FORCEPROP 1 LAST PART_NUMBER DGA^6000030
J 0
(-5845 3309);
DISPLAY 0.489362 (-5845 3309);
PAINT SKYBLUE (-5845 3309);
FORCEPROP 2 LAST CDS_LIB pure_quanta
J 0
(-4750 2200);
DISPLAY INVISIBLE (-4750 2200);
FORCEPROP 1 LAST NEEDS_NO_SIZE TRUE
J 0
(-4750 2200);
DISPLAY 0.723404 (-4750 2200);
PAINT GREEN (-4750 2200);
DISPLAY INVISIBLE (-4750 2200);
FORCEPROP 1 LAST CDS_LMAN_SYM_OUTLINE -1100,950,1100,-950
J 0
(-4750 2200);
DISPLAY 0.468085 (-4750 2200);
PAINT GREEN (-4750 2200);
DISPLAY INVISIBLE (-4750 2200);
FORCEPROP 1 LAST PATH I216
J 0
(-4750 2200);
DISPLAY 0.723404 (-4750 2200);
PAINT GREEN (-4750 2200);
DISPLAY INVISIBLE (-4750 2200);
FORCEADD OFFPAGE..2
(-1825 6050);
FORCEPROP 2 LAST $XR0 49 
J 0
(-1636 6050);
DISPLAY 0.638298 (-1636 6050);
PAINT MONO (-1636 6050);
FORCEPROP 2 LAST CDS_LIB standard
J 0
(-1825 6050);
DISPLAY INVISIBLE (-1825 6050);
FORCEPROP 1 LAST OFFPAGE TRUE
J 0
(-1500 5925);
DISPLAY 0.872340 (-1500 5925);
PAINT GREEN (-1500 5925);
DISPLAY INVISIBLE (-1500 5925);
FORCEPROP 1 LAST COMMENT_BODY TRUE
J 0
(-1870 5955);
DISPLAY 0.872340 (-1870 5955);
PAINT GREEN (-1870 5955);
DISPLAY INVISIBLE (-1870 5955);
FORCEPROP 2 LAST PATH I217
J 0
(-1625 6100);
DISPLAY 1.021277 (-1625 6100);
DISPLAY INVISIBLE (-1625 6100);
FORCEADD OFFPAGE..2
(-1825 6000);
FORCEPROP 2 LAST $XR0 49 
J 0
(-1636 6000);
DISPLAY 0.638298 (-1636 6000);
PAINT MONO (-1636 6000);
FORCEPROP 2 LAST CDS_LIB standard
J 0
(-1825 6000);
DISPLAY INVISIBLE (-1825 6000);
FORCEPROP 1 LAST OFFPAGE TRUE
J 0
(-1500 5875);
DISPLAY 0.872340 (-1500 5875);
PAINT GREEN (-1500 5875);
DISPLAY INVISIBLE (-1500 5875);
FORCEPROP 1 LAST COMMENT_BODY TRUE
J 0
(-1870 5905);
DISPLAY 0.872340 (-1870 5905);
PAINT GREEN (-1870 5905);
DISPLAY INVISIBLE (-1870 5905);
FORCEPROP 2 LAST PATH I218
J 0
(-1625 6050);
DISPLAY 1.021277 (-1625 6050);
DISPLAY INVISIBLE (-1625 6050);
FORCEADD TAP..6
R 2
(-2950 5775);
FORCEPROP 3 LASTPIN (-3000 5775) SIG_NAME GMI_CPU0_G2_CPU1_G0_TX_DN<0>
J 0
(-2990 5785);
DISPLAY 0.659574 (-2990 5785);
PAINT MONO (-2990 5785);
DISPLAY INVISIBLE (-2990 5785);
FORCEPROP 1 LASTPIN (-3000 5775) BN 0
J 2
(-2948 5783);
DISPLAY 0.489362 (-2948 5783);
PAINT MONO (-2948 5783);
FORCEPROP 2 LAST BOM_COST IO_SLOT
J 0
(-3450 5875);
DISPLAY 0.829787 (-3450 5875);
DISPLAY INVISIBLE (-3450 5875);
FORCEPROP 2 LAST CDS_LIB mstr_standard
J 0
(-2950 5775);
DISPLAY INVISIBLE (-2950 5775);
FORCEPROP 1 LAST BODY_TYPE PLUMBING
J 2
(-2950 5725);
DISPLAY 0.702128 (-2950 5725);
PAINT GREEN (-2950 5725);
DISPLAY INVISIBLE (-2950 5725);
FORCEPROP 1 LAST HDL_TAP TRUE
J 2
(-3275 5650);
DISPLAY 0.702128 (-3275 5650);
PAINT GREEN (-3275 5650);
DISPLAY INVISIBLE (-3275 5650);
FORCEPROP 1 LAST PATH I219
J 2
(-2948 5775);
DISPLAY 0.872340 (-2948 5775);
PAINT GREEN (-2948 5775);
DISPLAY INVISIBLE (-2948 5775);
FORCEPROP 2 LAST ROOM RISER1
J 0
(-3450 5825);
DISPLAY 0.829787 (-3450 5825);
PAINT RED (-3450 5825);
DISPLAY INVISIBLE (-3450 5825);
FORCEADD TAP..6
R 2
(-2950 5675);
FORCEPROP 3 LASTPIN (-3000 5675) SIG_NAME GMI_CPU0_G2_CPU1_G0_TX_DN<1>
J 0
(-2990 5685);
DISPLAY 0.659574 (-2990 5685);
PAINT MONO (-2990 5685);
DISPLAY INVISIBLE (-2990 5685);
FORCEPROP 1 LASTPIN (-3000 5675) BN 1
J 2
(-2948 5683);
DISPLAY 0.489362 (-2948 5683);
PAINT MONO (-2948 5683);
FORCEPROP 2 LAST CDS_LIB mstr_standard
J 0
(-2950 5675);
DISPLAY INVISIBLE (-2950 5675);
FORCEPROP 2 LAST BOM_COST IO_SLOT
J 0
(-3450 5775);
DISPLAY 0.829787 (-3450 5775);
DISPLAY INVISIBLE (-3450 5775);
FORCEPROP 1 LAST BODY_TYPE PLUMBING
J 2
(-2950 5625);
DISPLAY 0.702128 (-2950 5625);
PAINT GREEN (-2950 5625);
DISPLAY INVISIBLE (-2950 5625);
FORCEPROP 1 LAST HDL_TAP TRUE
J 2
(-3275 5550);
DISPLAY 0.702128 (-3275 5550);
PAINT GREEN (-3275 5550);
DISPLAY INVISIBLE (-3275 5550);
FORCEPROP 1 LAST PATH I220
J 2
(-2948 5675);
DISPLAY 0.872340 (-2948 5675);
PAINT GREEN (-2948 5675);
DISPLAY INVISIBLE (-2948 5675);
FORCEPROP 2 LAST ROOM RISER1
J 0
(-3450 5725);
DISPLAY 0.829787 (-3450 5725);
PAINT RED (-3450 5725);
DISPLAY INVISIBLE (-3450 5725);
FORCEADD TAP..6
R 2
(-3100 5825);
FORCEPROP 3 LASTPIN (-3150 5825) SIG_NAME GMI_CPU0_G2_CPU1_G0_TX_DP<0>
J 0
(-3140 5835);
DISPLAY 0.659574 (-3140 5835);
PAINT MONO (-3140 5835);
DISPLAY INVISIBLE (-3140 5835);
FORCEPROP 1 LASTPIN (-3150 5825) BN 0
J 2
(-3098 5833);
DISPLAY 0.489362 (-3098 5833);
PAINT MONO (-3098 5833);
FORCEPROP 2 LAST CDS_LIB mstr_standard
J 0
(-3100 5825);
DISPLAY INVISIBLE (-3100 5825);
FORCEPROP 2 LAST BOM_COST IO_SLOT
J 0
(-3600 5925);
DISPLAY 0.829787 (-3600 5925);
DISPLAY INVISIBLE (-3600 5925);
FORCEPROP 1 LAST BODY_TYPE PLUMBING
J 2
(-3100 5775);
DISPLAY 0.702128 (-3100 5775);
PAINT GREEN (-3100 5775);
DISPLAY INVISIBLE (-3100 5775);
FORCEPROP 1 LAST HDL_TAP TRUE
J 2
(-3425 5700);
DISPLAY 0.702128 (-3425 5700);
PAINT GREEN (-3425 5700);
DISPLAY INVISIBLE (-3425 5700);
FORCEPROP 1 LAST PATH I221
J 2
(-3098 5825);
DISPLAY 0.872340 (-3098 5825);
PAINT GREEN (-3098 5825);
DISPLAY INVISIBLE (-3098 5825);
FORCEPROP 2 LAST ROOM RISER1
J 0
(-3600 5875);
DISPLAY 0.829787 (-3600 5875);
PAINT RED (-3600 5875);
DISPLAY INVISIBLE (-3600 5875);
FORCEADD TAP..6
R 2
(-3100 5725);
FORCEPROP 3 LASTPIN (-3150 5725) SIG_NAME GMI_CPU0_G2_CPU1_G0_TX_DP<1>
J 0
(-3140 5735);
DISPLAY 0.659574 (-3140 5735);
PAINT MONO (-3140 5735);
DISPLAY INVISIBLE (-3140 5735);
FORCEPROP 1 LASTPIN (-3150 5725) BN 1
J 2
(-3098 5733);
DISPLAY 0.489362 (-3098 5733);
PAINT MONO (-3098 5733);
FORCEPROP 2 LAST CDS_LIB mstr_standard
J 0
(-3100 5725);
DISPLAY INVISIBLE (-3100 5725);
FORCEPROP 2 LAST BOM_COST IO_SLOT
J 0
(-3600 5825);
DISPLAY 0.829787 (-3600 5825);
DISPLAY INVISIBLE (-3600 5825);
FORCEPROP 1 LAST BODY_TYPE PLUMBING
J 2
(-3100 5675);
DISPLAY 0.702128 (-3100 5675);
PAINT GREEN (-3100 5675);
DISPLAY INVISIBLE (-3100 5675);
FORCEPROP 1 LAST HDL_TAP TRUE
J 2
(-3425 5600);
DISPLAY 0.702128 (-3425 5600);
PAINT GREEN (-3425 5600);
DISPLAY INVISIBLE (-3425 5600);
FORCEPROP 1 LAST PATH I222
J 2
(-3098 5725);
DISPLAY 0.872340 (-3098 5725);
PAINT GREEN (-3098 5725);
DISPLAY INVISIBLE (-3098 5725);
FORCEPROP 2 LAST ROOM RISER1
J 0
(-3600 5775);
DISPLAY 0.829787 (-3600 5775);
PAINT RED (-3600 5775);
DISPLAY INVISIBLE (-3600 5775);
FORCEADD TAP..6
R 2
(-2950 5575);
FORCEPROP 3 LASTPIN (-3000 5575) SIG_NAME GMI_CPU0_G2_CPU1_G0_TX_DN<2>
J 0
(-2990 5585);
DISPLAY 0.659574 (-2990 5585);
PAINT MONO (-2990 5585);
DISPLAY INVISIBLE (-2990 5585);
FORCEPROP 1 LASTPIN (-3000 5575) BN 2
J 2
(-2948 5583);
DISPLAY 0.489362 (-2948 5583);
PAINT MONO (-2948 5583);
FORCEPROP 2 LAST CDS_LIB standard
J 0
(-2950 5575);
DISPLAY INVISIBLE (-2950 5575);
FORCEPROP 2 LAST BOM_COST IO_SLOT
J 0
(-3450 5675);
DISPLAY 0.829787 (-3450 5675);
DISPLAY INVISIBLE (-3450 5675);
FORCEPROP 1 LAST BODY_TYPE PLUMBING
J 2
(-2950 5525);
DISPLAY 0.702128 (-2950 5525);
PAINT GREEN (-2950 5525);
DISPLAY INVISIBLE (-2950 5525);
FORCEPROP 1 LAST HDL_TAP TRUE
J 2
(-3275 5450);
DISPLAY 0.702128 (-3275 5450);
PAINT GREEN (-3275 5450);
DISPLAY INVISIBLE (-3275 5450);
FORCEPROP 1 LAST PATH I223
J 2
(-2948 5575);
DISPLAY 0.872340 (-2948 5575);
PAINT GREEN (-2948 5575);
DISPLAY INVISIBLE (-2948 5575);
FORCEPROP 2 LAST ROOM RISER1
J 0
(-3450 5625);
DISPLAY 0.829787 (-3450 5625);
PAINT RED (-3450 5625);
DISPLAY INVISIBLE (-3450 5625);
FORCEADD TAP..6
R 2
(-2950 5475);
FORCEPROP 3 LASTPIN (-3000 5475) SIG_NAME GMI_CPU0_G2_CPU1_G0_TX_DN<3>
J 0
(-2990 5485);
DISPLAY 0.659574 (-2990 5485);
PAINT MONO (-2990 5485);
DISPLAY INVISIBLE (-2990 5485);
FORCEPROP 1 LASTPIN (-3000 5475) BN 3
J 2
(-2948 5483);
DISPLAY 0.489362 (-2948 5483);
PAINT MONO (-2948 5483);
FORCEPROP 2 LAST CDS_LIB standard
J 0
(-2950 5475);
DISPLAY INVISIBLE (-2950 5475);
FORCEPROP 2 LAST BOM_COST IO_SLOT
J 0
(-3450 5575);
DISPLAY 0.829787 (-3450 5575);
DISPLAY INVISIBLE (-3450 5575);
FORCEPROP 1 LAST BODY_TYPE PLUMBING
J 2
(-2950 5425);
DISPLAY 0.702128 (-2950 5425);
PAINT GREEN (-2950 5425);
DISPLAY INVISIBLE (-2950 5425);
FORCEPROP 1 LAST HDL_TAP TRUE
J 2
(-3275 5350);
DISPLAY 0.702128 (-3275 5350);
PAINT GREEN (-3275 5350);
DISPLAY INVISIBLE (-3275 5350);
FORCEPROP 1 LAST PATH I224
J 2
(-2948 5475);
DISPLAY 0.872340 (-2948 5475);
PAINT GREEN (-2948 5475);
DISPLAY INVISIBLE (-2948 5475);
FORCEPROP 2 LAST ROOM RISER1
J 0
(-3450 5525);
DISPLAY 0.829787 (-3450 5525);
PAINT RED (-3450 5525);
DISPLAY INVISIBLE (-3450 5525);
FORCEADD TAP..6
R 2
(-3100 5625);
FORCEPROP 3 LASTPIN (-3150 5625) SIG_NAME GMI_CPU0_G2_CPU1_G0_TX_DP<2>
J 0
(-3140 5635);
DISPLAY 0.659574 (-3140 5635);
PAINT MONO (-3140 5635);
DISPLAY INVISIBLE (-3140 5635);
FORCEPROP 1 LASTPIN (-3150 5625) BN 2
J 2
(-3098 5633);
DISPLAY 0.489362 (-3098 5633);
PAINT MONO (-3098 5633);
FORCEPROP 2 LAST CDS_LIB standard
J 0
(-3100 5625);
DISPLAY INVISIBLE (-3100 5625);
FORCEPROP 2 LAST BOM_COST IO_SLOT
J 0
(-3600 5725);
DISPLAY 0.829787 (-3600 5725);
DISPLAY INVISIBLE (-3600 5725);
FORCEPROP 1 LAST BODY_TYPE PLUMBING
J 2
(-3100 5575);
DISPLAY 0.702128 (-3100 5575);
PAINT GREEN (-3100 5575);
DISPLAY INVISIBLE (-3100 5575);
FORCEPROP 1 LAST HDL_TAP TRUE
J 2
(-3425 5500);
DISPLAY 0.702128 (-3425 5500);
PAINT GREEN (-3425 5500);
DISPLAY INVISIBLE (-3425 5500);
FORCEPROP 1 LAST PATH I225
J 2
(-3098 5625);
DISPLAY 0.872340 (-3098 5625);
PAINT GREEN (-3098 5625);
DISPLAY INVISIBLE (-3098 5625);
FORCEPROP 2 LAST ROOM RISER1
J 0
(-3600 5675);
DISPLAY 0.829787 (-3600 5675);
PAINT RED (-3600 5675);
DISPLAY INVISIBLE (-3600 5675);
FORCEADD TAP..6
R 2
(-3100 5525);
FORCEPROP 3 LASTPIN (-3150 5525) SIG_NAME GMI_CPU0_G2_CPU1_G0_TX_DP<3>
J 0
(-3140 5535);
DISPLAY 0.659574 (-3140 5535);
PAINT MONO (-3140 5535);
DISPLAY INVISIBLE (-3140 5535);
FORCEPROP 1 LASTPIN (-3150 5525) BN 3
J 2
(-3098 5533);
DISPLAY 0.489362 (-3098 5533);
PAINT MONO (-3098 5533);
FORCEPROP 2 LAST CDS_LIB standard
J 0
(-3100 5525);
DISPLAY INVISIBLE (-3100 5525);
FORCEPROP 2 LAST BOM_COST IO_SLOT
J 0
(-3600 5625);
DISPLAY 0.829787 (-3600 5625);
DISPLAY INVISIBLE (-3600 5625);
FORCEPROP 1 LAST BODY_TYPE PLUMBING
J 2
(-3100 5475);
DISPLAY 0.702128 (-3100 5475);
PAINT GREEN (-3100 5475);
DISPLAY INVISIBLE (-3100 5475);
FORCEPROP 1 LAST HDL_TAP TRUE
J 2
(-3425 5400);
DISPLAY 0.702128 (-3425 5400);
PAINT GREEN (-3425 5400);
DISPLAY INVISIBLE (-3425 5400);
FORCEPROP 1 LAST PATH I226
J 2
(-3098 5525);
DISPLAY 0.872340 (-3098 5525);
PAINT GREEN (-3098 5525);
DISPLAY INVISIBLE (-3098 5525);
FORCEPROP 2 LAST ROOM RISER1
J 0
(-3600 5575);
DISPLAY 0.829787 (-3600 5575);
PAINT RED (-3600 5575);
DISPLAY INVISIBLE (-3600 5575);
FORCEADD TAP..6
R 2
(-3100 5425);
FORCEPROP 3 LASTPIN (-3150 5425) SIG_NAME GMI_CPU0_G2_CPU1_G0_TX_DP<4>
J 0
(-3140 5435);
DISPLAY 0.659574 (-3140 5435);
PAINT MONO (-3140 5435);
DISPLAY INVISIBLE (-3140 5435);
FORCEPROP 1 LASTPIN (-3150 5425) BN 4
J 2
(-3098 5433);
DISPLAY 0.489362 (-3098 5433);
PAINT MONO (-3098 5433);
FORCEPROP 2 LAST CDS_LIB standard
J 0
(-3100 5425);
DISPLAY INVISIBLE (-3100 5425);
FORCEPROP 2 LAST BOM_COST IO_SLOT
J 0
(-3600 5525);
DISPLAY 0.829787 (-3600 5525);
DISPLAY INVISIBLE (-3600 5525);
FORCEPROP 1 LAST BODY_TYPE PLUMBING
J 2
(-3100 5375);
DISPLAY 0.702128 (-3100 5375);
PAINT GREEN (-3100 5375);
DISPLAY INVISIBLE (-3100 5375);
FORCEPROP 1 LAST HDL_TAP TRUE
J 2
(-3425 5300);
DISPLAY 0.702128 (-3425 5300);
PAINT GREEN (-3425 5300);
DISPLAY INVISIBLE (-3425 5300);
FORCEPROP 1 LAST PATH I227
J 2
(-3098 5425);
DISPLAY 0.872340 (-3098 5425);
PAINT GREEN (-3098 5425);
DISPLAY INVISIBLE (-3098 5425);
FORCEPROP 2 LAST ROOM RISER1
J 0
(-3600 5475);
DISPLAY 0.829787 (-3600 5475);
PAINT RED (-3600 5475);
DISPLAY INVISIBLE (-3600 5475);
FORCEADD TAP..6
R 2
(-2950 5275);
FORCEPROP 3 LASTPIN (-3000 5275) SIG_NAME GMI_CPU0_G2_CPU1_G0_TX_DN<5>
J 0
(-2990 5285);
DISPLAY 0.659574 (-2990 5285);
PAINT MONO (-2990 5285);
DISPLAY INVISIBLE (-2990 5285);
FORCEPROP 1 LASTPIN (-3000 5275) BN 5
J 2
(-2948 5283);
DISPLAY 0.489362 (-2948 5283);
PAINT MONO (-2948 5283);
FORCEPROP 2 LAST CDS_LIB standard
J 0
(-2950 5275);
DISPLAY INVISIBLE (-2950 5275);
FORCEPROP 2 LAST BOM_COST IO_SLOT
J 0
(-3450 5375);
DISPLAY 0.829787 (-3450 5375);
DISPLAY INVISIBLE (-3450 5375);
FORCEPROP 1 LAST BODY_TYPE PLUMBING
J 2
(-2950 5225);
DISPLAY 0.702128 (-2950 5225);
PAINT GREEN (-2950 5225);
DISPLAY INVISIBLE (-2950 5225);
FORCEPROP 1 LAST HDL_TAP TRUE
J 2
(-3275 5150);
DISPLAY 0.702128 (-3275 5150);
PAINT GREEN (-3275 5150);
DISPLAY INVISIBLE (-3275 5150);
FORCEPROP 1 LAST PATH I228
J 2
(-2948 5275);
DISPLAY 0.872340 (-2948 5275);
PAINT GREEN (-2948 5275);
DISPLAY INVISIBLE (-2948 5275);
FORCEPROP 2 LAST ROOM RISER1
J 0
(-3450 5325);
DISPLAY 0.829787 (-3450 5325);
PAINT RED (-3450 5325);
DISPLAY INVISIBLE (-3450 5325);
FORCEADD TAP..6
R 2
(-2950 5375);
FORCEPROP 3 LASTPIN (-3000 5375) SIG_NAME GMI_CPU0_G2_CPU1_G0_TX_DN<4>
J 0
(-2990 5385);
DISPLAY 0.659574 (-2990 5385);
PAINT MONO (-2990 5385);
DISPLAY INVISIBLE (-2990 5385);
FORCEPROP 1 LASTPIN (-3000 5375) BN 4
J 2
(-2948 5383);
DISPLAY 0.489362 (-2948 5383);
PAINT MONO (-2948 5383);
FORCEPROP 2 LAST CDS_LIB standard
J 0
(-2950 5375);
DISPLAY INVISIBLE (-2950 5375);
FORCEPROP 2 LAST BOM_COST IO_SLOT
J 0
(-3450 5475);
DISPLAY 0.829787 (-3450 5475);
DISPLAY INVISIBLE (-3450 5475);
FORCEPROP 1 LAST BODY_TYPE PLUMBING
J 2
(-2950 5325);
DISPLAY 0.702128 (-2950 5325);
PAINT GREEN (-2950 5325);
DISPLAY INVISIBLE (-2950 5325);
FORCEPROP 1 LAST HDL_TAP TRUE
J 2
(-3275 5250);
DISPLAY 0.702128 (-3275 5250);
PAINT GREEN (-3275 5250);
DISPLAY INVISIBLE (-3275 5250);
FORCEPROP 1 LAST PATH I229
J 2
(-2948 5375);
DISPLAY 0.872340 (-2948 5375);
PAINT GREEN (-2948 5375);
DISPLAY INVISIBLE (-2948 5375);
FORCEPROP 2 LAST ROOM RISER1
J 0
(-3450 5425);
DISPLAY 0.829787 (-3450 5425);
PAINT RED (-3450 5425);
DISPLAY INVISIBLE (-3450 5425);
FORCEADD TAP..6
R 2
(-2950 5175);
FORCEPROP 3 LASTPIN (-3000 5175) SIG_NAME GMI_CPU0_G2_CPU1_G0_TX_DN<6>
J 0
(-2990 5185);
DISPLAY 0.659574 (-2990 5185);
PAINT MONO (-2990 5185);
DISPLAY INVISIBLE (-2990 5185);
FORCEPROP 1 LASTPIN (-3000 5175) BN 6
J 2
(-2948 5183);
DISPLAY 0.489362 (-2948 5183);
PAINT MONO (-2948 5183);
FORCEPROP 2 LAST CDS_LIB standard
J 0
(-2950 5175);
DISPLAY INVISIBLE (-2950 5175);
FORCEPROP 2 LAST BOM_COST IO_SLOT
J 0
(-3450 5275);
DISPLAY 0.829787 (-3450 5275);
DISPLAY INVISIBLE (-3450 5275);
FORCEPROP 1 LAST BODY_TYPE PLUMBING
J 2
(-2950 5125);
DISPLAY 0.702128 (-2950 5125);
PAINT GREEN (-2950 5125);
DISPLAY INVISIBLE (-2950 5125);
FORCEPROP 1 LAST HDL_TAP TRUE
J 2
(-3275 5050);
DISPLAY 0.702128 (-3275 5050);
PAINT GREEN (-3275 5050);
DISPLAY INVISIBLE (-3275 5050);
FORCEPROP 1 LAST PATH I230
J 2
(-2948 5175);
DISPLAY 0.872340 (-2948 5175);
PAINT GREEN (-2948 5175);
DISPLAY INVISIBLE (-2948 5175);
FORCEPROP 2 LAST ROOM RISER1
J 0
(-3450 5225);
DISPLAY 0.829787 (-3450 5225);
PAINT RED (-3450 5225);
DISPLAY INVISIBLE (-3450 5225);
FORCEADD TAP..6
R 2
(-3100 5125);
FORCEPROP 3 LASTPIN (-3150 5125) SIG_NAME GMI_CPU0_G2_CPU1_G0_TX_DP<7>
J 0
(-3140 5135);
DISPLAY 0.659574 (-3140 5135);
PAINT MONO (-3140 5135);
DISPLAY INVISIBLE (-3140 5135);
FORCEPROP 1 LASTPIN (-3150 5125) BN 7
J 2
(-3098 5133);
DISPLAY 0.489362 (-3098 5133);
PAINT MONO (-3098 5133);
FORCEPROP 2 LAST CDS_LIB standard
J 0
(-3100 5125);
DISPLAY INVISIBLE (-3100 5125);
FORCEPROP 2 LAST BOM_COST IO_SLOT
J 0
(-3600 5225);
DISPLAY 0.829787 (-3600 5225);
DISPLAY INVISIBLE (-3600 5225);
FORCEPROP 1 LAST BODY_TYPE PLUMBING
J 2
(-3100 5075);
DISPLAY 0.702128 (-3100 5075);
PAINT GREEN (-3100 5075);
DISPLAY INVISIBLE (-3100 5075);
FORCEPROP 1 LAST HDL_TAP TRUE
J 2
(-3425 5000);
DISPLAY 0.702128 (-3425 5000);
PAINT GREEN (-3425 5000);
DISPLAY INVISIBLE (-3425 5000);
FORCEPROP 1 LAST PATH I231
J 2
(-3098 5125);
DISPLAY 0.872340 (-3098 5125);
PAINT GREEN (-3098 5125);
DISPLAY INVISIBLE (-3098 5125);
FORCEPROP 2 LAST ROOM RISER1
J 0
(-3600 5175);
DISPLAY 0.829787 (-3600 5175);
PAINT RED (-3600 5175);
DISPLAY INVISIBLE (-3600 5175);
FORCEADD TAP..6
R 2
(-3100 5325);
FORCEPROP 3 LASTPIN (-3150 5325) SIG_NAME GMI_CPU0_G2_CPU1_G0_TX_DP<5>
J 0
(-3140 5335);
DISPLAY 0.659574 (-3140 5335);
PAINT MONO (-3140 5335);
DISPLAY INVISIBLE (-3140 5335);
FORCEPROP 1 LASTPIN (-3150 5325) BN 5
J 2
(-3098 5333);
DISPLAY 0.489362 (-3098 5333);
PAINT MONO (-3098 5333);
FORCEPROP 2 LAST CDS_LIB standard
J 0
(-3100 5325);
DISPLAY INVISIBLE (-3100 5325);
FORCEPROP 2 LAST BOM_COST IO_SLOT
J 0
(-3600 5425);
DISPLAY 0.829787 (-3600 5425);
DISPLAY INVISIBLE (-3600 5425);
FORCEPROP 1 LAST BODY_TYPE PLUMBING
J 2
(-3100 5275);
DISPLAY 0.702128 (-3100 5275);
PAINT GREEN (-3100 5275);
DISPLAY INVISIBLE (-3100 5275);
FORCEPROP 1 LAST HDL_TAP TRUE
J 2
(-3425 5200);
DISPLAY 0.702128 (-3425 5200);
PAINT GREEN (-3425 5200);
DISPLAY INVISIBLE (-3425 5200);
FORCEPROP 1 LAST PATH I232
J 2
(-3098 5325);
DISPLAY 0.872340 (-3098 5325);
PAINT GREEN (-3098 5325);
DISPLAY INVISIBLE (-3098 5325);
FORCEPROP 2 LAST ROOM RISER1
J 0
(-3600 5375);
DISPLAY 0.829787 (-3600 5375);
PAINT RED (-3600 5375);
DISPLAY INVISIBLE (-3600 5375);
FORCEADD TAP..6
R 2
(-3100 5225);
FORCEPROP 3 LASTPIN (-3150 5225) SIG_NAME GMI_CPU0_G2_CPU1_G0_TX_DP<6>
J 0
(-3140 5235);
DISPLAY 0.659574 (-3140 5235);
PAINT MONO (-3140 5235);
DISPLAY INVISIBLE (-3140 5235);
FORCEPROP 1 LASTPIN (-3150 5225) BN 6
J 2
(-3098 5233);
DISPLAY 0.489362 (-3098 5233);
PAINT MONO (-3098 5233);
FORCEPROP 2 LAST CDS_LIB standard
J 0
(-3100 5225);
DISPLAY INVISIBLE (-3100 5225);
FORCEPROP 2 LAST BOM_COST IO_SLOT
J 0
(-3600 5325);
DISPLAY 0.829787 (-3600 5325);
DISPLAY INVISIBLE (-3600 5325);
FORCEPROP 1 LAST BODY_TYPE PLUMBING
J 2
(-3100 5175);
DISPLAY 0.702128 (-3100 5175);
PAINT GREEN (-3100 5175);
DISPLAY INVISIBLE (-3100 5175);
FORCEPROP 1 LAST HDL_TAP TRUE
J 2
(-3425 5100);
DISPLAY 0.702128 (-3425 5100);
PAINT GREEN (-3425 5100);
DISPLAY INVISIBLE (-3425 5100);
FORCEPROP 1 LAST PATH I233
J 2
(-3098 5225);
DISPLAY 0.872340 (-3098 5225);
PAINT GREEN (-3098 5225);
DISPLAY INVISIBLE (-3098 5225);
FORCEPROP 2 LAST ROOM RISER1
J 0
(-3600 5275);
DISPLAY 0.829787 (-3600 5275);
PAINT RED (-3600 5275);
DISPLAY INVISIBLE (-3600 5275);
FORCEADD TAP..6
R 2
(-2950 5075);
FORCEPROP 3 LASTPIN (-3000 5075) SIG_NAME GMI_CPU0_G2_CPU1_G0_TX_DN<7>
J 0
(-2990 5085);
DISPLAY 0.659574 (-2990 5085);
PAINT MONO (-2990 5085);
DISPLAY INVISIBLE (-2990 5085);
FORCEPROP 1 LASTPIN (-3000 5075) BN 7
J 2
(-2948 5083);
DISPLAY 0.489362 (-2948 5083);
PAINT MONO (-2948 5083);
FORCEPROP 2 LAST CDS_LIB standard
J 0
(-2950 5075);
DISPLAY INVISIBLE (-2950 5075);
FORCEPROP 2 LAST BOM_COST IO_SLOT
J 0
(-3450 5175);
DISPLAY 0.829787 (-3450 5175);
DISPLAY INVISIBLE (-3450 5175);
FORCEPROP 1 LAST BODY_TYPE PLUMBING
J 2
(-2950 5025);
DISPLAY 0.702128 (-2950 5025);
PAINT GREEN (-2950 5025);
DISPLAY INVISIBLE (-2950 5025);
FORCEPROP 1 LAST HDL_TAP TRUE
J 2
(-3275 4950);
DISPLAY 0.702128 (-3275 4950);
PAINT GREEN (-3275 4950);
DISPLAY INVISIBLE (-3275 4950);
FORCEPROP 1 LAST PATH I234
J 2
(-2948 5075);
DISPLAY 0.872340 (-2948 5075);
PAINT GREEN (-2948 5075);
DISPLAY INVISIBLE (-2948 5075);
FORCEPROP 2 LAST ROOM RISER1
J 0
(-3450 5125);
DISPLAY 0.829787 (-3450 5125);
PAINT RED (-3450 5125);
DISPLAY INVISIBLE (-3450 5125);
FORCEADD TAP..6
R 2
(-2950 4875);
FORCEPROP 3 LASTPIN (-3000 4875) SIG_NAME GMI_CPU0_G2_CPU1_G0_TX_DN<9>
J 0
(-2990 4885);
DISPLAY 0.659574 (-2990 4885);
PAINT MONO (-2990 4885);
DISPLAY INVISIBLE (-2990 4885);
FORCEPROP 1 LASTPIN (-3000 4875) BN 9
J 2
(-2948 4883);
DISPLAY 0.489362 (-2948 4883);
PAINT MONO (-2948 4883);
FORCEPROP 2 LAST CDS_LIB standard
J 0
(-2950 4875);
DISPLAY INVISIBLE (-2950 4875);
FORCEPROP 2 LAST BOM_COST IO_SLOT
J 0
(-3450 4975);
DISPLAY 0.829787 (-3450 4975);
DISPLAY INVISIBLE (-3450 4975);
FORCEPROP 1 LAST BODY_TYPE PLUMBING
J 2
(-2950 4825);
DISPLAY 0.702128 (-2950 4825);
PAINT GREEN (-2950 4825);
DISPLAY INVISIBLE (-2950 4825);
FORCEPROP 1 LAST HDL_TAP TRUE
J 2
(-3275 4750);
DISPLAY 0.702128 (-3275 4750);
PAINT GREEN (-3275 4750);
DISPLAY INVISIBLE (-3275 4750);
FORCEPROP 1 LAST PATH I235
J 2
(-2948 4875);
DISPLAY 0.872340 (-2948 4875);
PAINT GREEN (-2948 4875);
DISPLAY INVISIBLE (-2948 4875);
FORCEPROP 2 LAST ROOM RISER1
J 0
(-3450 4925);
DISPLAY 0.829787 (-3450 4925);
PAINT RED (-3450 4925);
DISPLAY INVISIBLE (-3450 4925);
FORCEADD TAP..6
R 2
(-2950 4975);
FORCEPROP 3 LASTPIN (-3000 4975) SIG_NAME GMI_CPU0_G2_CPU1_G0_TX_DN<8>
J 0
(-2990 4985);
DISPLAY 0.659574 (-2990 4985);
PAINT MONO (-2990 4985);
DISPLAY INVISIBLE (-2990 4985);
FORCEPROP 1 LASTPIN (-3000 4975) BN 8
J 2
(-2948 4983);
DISPLAY 0.489362 (-2948 4983);
PAINT MONO (-2948 4983);
FORCEPROP 2 LAST CDS_LIB standard
J 0
(-2950 4975);
DISPLAY INVISIBLE (-2950 4975);
FORCEPROP 2 LAST BOM_COST IO_SLOT
J 0
(-3450 5075);
DISPLAY 0.829787 (-3450 5075);
DISPLAY INVISIBLE (-3450 5075);
FORCEPROP 1 LAST BODY_TYPE PLUMBING
J 2
(-2950 4925);
DISPLAY 0.702128 (-2950 4925);
PAINT GREEN (-2950 4925);
DISPLAY INVISIBLE (-2950 4925);
FORCEPROP 1 LAST HDL_TAP TRUE
J 2
(-3275 4850);
DISPLAY 0.702128 (-3275 4850);
PAINT GREEN (-3275 4850);
DISPLAY INVISIBLE (-3275 4850);
FORCEPROP 1 LAST PATH I236
J 2
(-2948 4975);
DISPLAY 0.872340 (-2948 4975);
PAINT GREEN (-2948 4975);
DISPLAY INVISIBLE (-2948 4975);
FORCEPROP 2 LAST ROOM RISER1
J 0
(-3450 5025);
DISPLAY 0.829787 (-3450 5025);
PAINT RED (-3450 5025);
DISPLAY INVISIBLE (-3450 5025);
FORCEADD TAP..6
R 2
(-3100 5025);
FORCEPROP 3 LASTPIN (-3150 5025) SIG_NAME GMI_CPU0_G2_CPU1_G0_TX_DP<8>
J 0
(-3140 5035);
DISPLAY 0.659574 (-3140 5035);
PAINT MONO (-3140 5035);
DISPLAY INVISIBLE (-3140 5035);
FORCEPROP 1 LASTPIN (-3150 5025) BN 8
J 2
(-3098 5033);
DISPLAY 0.489362 (-3098 5033);
PAINT MONO (-3098 5033);
FORCEPROP 2 LAST CDS_LIB standard
J 0
(-3100 5025);
DISPLAY INVISIBLE (-3100 5025);
FORCEPROP 2 LAST BOM_COST IO_SLOT
J 0
(-3600 5125);
DISPLAY 0.829787 (-3600 5125);
DISPLAY INVISIBLE (-3600 5125);
FORCEPROP 1 LAST BODY_TYPE PLUMBING
J 2
(-3100 4975);
DISPLAY 0.702128 (-3100 4975);
PAINT GREEN (-3100 4975);
DISPLAY INVISIBLE (-3100 4975);
FORCEPROP 1 LAST HDL_TAP TRUE
J 2
(-3425 4900);
DISPLAY 0.702128 (-3425 4900);
PAINT GREEN (-3425 4900);
DISPLAY INVISIBLE (-3425 4900);
FORCEPROP 1 LAST PATH I237
J 2
(-3098 5025);
DISPLAY 0.872340 (-3098 5025);
PAINT GREEN (-3098 5025);
DISPLAY INVISIBLE (-3098 5025);
FORCEPROP 2 LAST ROOM RISER1
J 0
(-3600 5075);
DISPLAY 0.829787 (-3600 5075);
PAINT RED (-3600 5075);
DISPLAY INVISIBLE (-3600 5075);
FORCEADD TAP..6
R 2
(-3100 4925);
FORCEPROP 3 LASTPIN (-3150 4925) SIG_NAME GMI_CPU0_G2_CPU1_G0_TX_DP<9>
J 0
(-3140 4935);
DISPLAY 0.659574 (-3140 4935);
PAINT MONO (-3140 4935);
DISPLAY INVISIBLE (-3140 4935);
FORCEPROP 1 LASTPIN (-3150 4925) BN 9
J 2
(-3098 4933);
DISPLAY 0.489362 (-3098 4933);
PAINT MONO (-3098 4933);
FORCEPROP 2 LAST CDS_LIB standard
J 0
(-3100 4925);
DISPLAY INVISIBLE (-3100 4925);
FORCEPROP 2 LAST BOM_COST IO_SLOT
J 0
(-3600 5025);
DISPLAY 0.829787 (-3600 5025);
DISPLAY INVISIBLE (-3600 5025);
FORCEPROP 1 LAST BODY_TYPE PLUMBING
J 2
(-3100 4875);
DISPLAY 0.702128 (-3100 4875);
PAINT GREEN (-3100 4875);
DISPLAY INVISIBLE (-3100 4875);
FORCEPROP 1 LAST HDL_TAP TRUE
J 2
(-3425 4800);
DISPLAY 0.702128 (-3425 4800);
PAINT GREEN (-3425 4800);
DISPLAY INVISIBLE (-3425 4800);
FORCEPROP 1 LAST PATH I238
J 2
(-3098 4925);
DISPLAY 0.872340 (-3098 4925);
PAINT GREEN (-3098 4925);
DISPLAY INVISIBLE (-3098 4925);
FORCEPROP 2 LAST ROOM RISER1
J 0
(-3600 4975);
DISPLAY 0.829787 (-3600 4975);
PAINT RED (-3600 4975);
DISPLAY INVISIBLE (-3600 4975);
FORCEADD TAP..6
R 2
(-2950 4775);
FORCEPROP 3 LASTPIN (-3000 4775) SIG_NAME GMI_CPU0_G2_CPU1_G0_TX_DN<10>
J 0
(-2990 4785);
DISPLAY 0.659574 (-2990 4785);
PAINT MONO (-2990 4785);
DISPLAY INVISIBLE (-2990 4785);
FORCEPROP 1 LASTPIN (-3000 4775) BN 10
J 2
(-2948 4783);
DISPLAY 0.489362 (-2948 4783);
PAINT MONO (-2948 4783);
FORCEPROP 2 LAST CDS_LIB standard
J 0
(-2950 4775);
DISPLAY INVISIBLE (-2950 4775);
FORCEPROP 2 LAST BOM_COST IO_SLOT
J 0
(-3450 4875);
DISPLAY 0.829787 (-3450 4875);
DISPLAY INVISIBLE (-3450 4875);
FORCEPROP 1 LAST BODY_TYPE PLUMBING
J 2
(-2950 4725);
DISPLAY 0.702128 (-2950 4725);
PAINT GREEN (-2950 4725);
DISPLAY INVISIBLE (-2950 4725);
FORCEPROP 1 LAST HDL_TAP TRUE
J 2
(-3275 4650);
DISPLAY 0.702128 (-3275 4650);
PAINT GREEN (-3275 4650);
DISPLAY INVISIBLE (-3275 4650);
FORCEPROP 1 LAST PATH I239
J 2
(-2948 4775);
DISPLAY 0.872340 (-2948 4775);
PAINT GREEN (-2948 4775);
DISPLAY INVISIBLE (-2948 4775);
FORCEPROP 2 LAST ROOM RISER1
J 0
(-3450 4825);
DISPLAY 0.829787 (-3450 4825);
PAINT RED (-3450 4825);
DISPLAY INVISIBLE (-3450 4825);
FORCEADD TAP..6
R 2
(-2950 4675);
FORCEPROP 3 LASTPIN (-3000 4675) SIG_NAME GMI_CPU0_G2_CPU1_G0_TX_DN<11>
J 0
(-2990 4685);
DISPLAY 0.659574 (-2990 4685);
PAINT MONO (-2990 4685);
DISPLAY INVISIBLE (-2990 4685);
FORCEPROP 1 LASTPIN (-3000 4675) BN 11
J 2
(-2948 4683);
DISPLAY 0.489362 (-2948 4683);
PAINT MONO (-2948 4683);
FORCEPROP 2 LAST CDS_LIB standard
J 0
(-2950 4675);
DISPLAY INVISIBLE (-2950 4675);
FORCEPROP 2 LAST BOM_COST IO_SLOT
J 0
(-3450 4775);
DISPLAY 0.829787 (-3450 4775);
DISPLAY INVISIBLE (-3450 4775);
FORCEPROP 1 LAST BODY_TYPE PLUMBING
J 2
(-2950 4625);
DISPLAY 0.702128 (-2950 4625);
PAINT GREEN (-2950 4625);
DISPLAY INVISIBLE (-2950 4625);
FORCEPROP 1 LAST HDL_TAP TRUE
J 2
(-3275 4550);
DISPLAY 0.702128 (-3275 4550);
PAINT GREEN (-3275 4550);
DISPLAY INVISIBLE (-3275 4550);
FORCEPROP 1 LAST PATH I240
J 2
(-2948 4675);
DISPLAY 0.872340 (-2948 4675);
PAINT GREEN (-2948 4675);
DISPLAY INVISIBLE (-2948 4675);
FORCEPROP 2 LAST ROOM RISER1
J 0
(-3450 4725);
DISPLAY 0.829787 (-3450 4725);
PAINT RED (-3450 4725);
DISPLAY INVISIBLE (-3450 4725);
FORCEADD TAP..6
R 2
(-3100 4625);
FORCEPROP 3 LASTPIN (-3150 4625) SIG_NAME GMI_CPU0_G2_CPU1_G0_TX_DP<12>
J 0
(-3140 4635);
DISPLAY 0.659574 (-3140 4635);
PAINT MONO (-3140 4635);
DISPLAY INVISIBLE (-3140 4635);
FORCEPROP 1 LASTPIN (-3150 4625) BN 12
J 2
(-3098 4633);
DISPLAY 0.489362 (-3098 4633);
PAINT MONO (-3098 4633);
FORCEPROP 2 LAST CDS_LIB standard
J 0
(-3100 4625);
DISPLAY INVISIBLE (-3100 4625);
FORCEPROP 2 LAST BOM_COST IO_SLOT
J 0
(-3600 4725);
DISPLAY 0.829787 (-3600 4725);
DISPLAY INVISIBLE (-3600 4725);
FORCEPROP 1 LAST BODY_TYPE PLUMBING
J 2
(-3100 4575);
DISPLAY 0.702128 (-3100 4575);
PAINT GREEN (-3100 4575);
DISPLAY INVISIBLE (-3100 4575);
FORCEPROP 1 LAST HDL_TAP TRUE
J 2
(-3425 4500);
DISPLAY 0.702128 (-3425 4500);
PAINT GREEN (-3425 4500);
DISPLAY INVISIBLE (-3425 4500);
FORCEPROP 1 LAST PATH I241
J 2
(-3098 4625);
DISPLAY 0.872340 (-3098 4625);
PAINT GREEN (-3098 4625);
DISPLAY INVISIBLE (-3098 4625);
FORCEPROP 2 LAST ROOM RISER1
J 0
(-3600 4675);
DISPLAY 0.829787 (-3600 4675);
PAINT RED (-3600 4675);
DISPLAY INVISIBLE (-3600 4675);
FORCEADD TAP..6
R 2
(-3100 4825);
FORCEPROP 3 LASTPIN (-3150 4825) SIG_NAME GMI_CPU0_G2_CPU1_G0_TX_DP<10>
J 0
(-3140 4835);
DISPLAY 0.659574 (-3140 4835);
PAINT MONO (-3140 4835);
DISPLAY INVISIBLE (-3140 4835);
FORCEPROP 1 LASTPIN (-3150 4825) BN 10
J 2
(-3098 4833);
DISPLAY 0.489362 (-3098 4833);
PAINT MONO (-3098 4833);
FORCEPROP 2 LAST CDS_LIB standard
J 0
(-3100 4825);
DISPLAY INVISIBLE (-3100 4825);
FORCEPROP 2 LAST BOM_COST IO_SLOT
J 0
(-3600 4925);
DISPLAY 0.829787 (-3600 4925);
DISPLAY INVISIBLE (-3600 4925);
FORCEPROP 1 LAST BODY_TYPE PLUMBING
J 2
(-3100 4775);
DISPLAY 0.702128 (-3100 4775);
PAINT GREEN (-3100 4775);
DISPLAY INVISIBLE (-3100 4775);
FORCEPROP 1 LAST HDL_TAP TRUE
J 2
(-3425 4700);
DISPLAY 0.702128 (-3425 4700);
PAINT GREEN (-3425 4700);
DISPLAY INVISIBLE (-3425 4700);
FORCEPROP 1 LAST PATH I242
J 2
(-3098 4825);
DISPLAY 0.872340 (-3098 4825);
PAINT GREEN (-3098 4825);
DISPLAY INVISIBLE (-3098 4825);
FORCEPROP 2 LAST ROOM RISER1
J 0
(-3600 4875);
DISPLAY 0.829787 (-3600 4875);
PAINT RED (-3600 4875);
DISPLAY INVISIBLE (-3600 4875);
FORCEADD TAP..6
R 2
(-3100 4725);
FORCEPROP 3 LASTPIN (-3150 4725) SIG_NAME GMI_CPU0_G2_CPU1_G0_TX_DP<11>
J 0
(-3140 4735);
DISPLAY 0.659574 (-3140 4735);
PAINT MONO (-3140 4735);
DISPLAY INVISIBLE (-3140 4735);
FORCEPROP 1 LASTPIN (-3150 4725) BN 11
J 2
(-3098 4733);
DISPLAY 0.489362 (-3098 4733);
PAINT MONO (-3098 4733);
FORCEPROP 2 LAST CDS_LIB standard
J 0
(-3100 4725);
DISPLAY INVISIBLE (-3100 4725);
FORCEPROP 2 LAST BOM_COST IO_SLOT
J 0
(-3600 4825);
DISPLAY 0.829787 (-3600 4825);
DISPLAY INVISIBLE (-3600 4825);
FORCEPROP 1 LAST BODY_TYPE PLUMBING
J 2
(-3100 4675);
DISPLAY 0.702128 (-3100 4675);
PAINT GREEN (-3100 4675);
DISPLAY INVISIBLE (-3100 4675);
FORCEPROP 1 LAST HDL_TAP TRUE
J 2
(-3425 4600);
DISPLAY 0.702128 (-3425 4600);
PAINT GREEN (-3425 4600);
DISPLAY INVISIBLE (-3425 4600);
FORCEPROP 1 LAST PATH I243
J 2
(-3098 4725);
DISPLAY 0.872340 (-3098 4725);
PAINT GREEN (-3098 4725);
DISPLAY INVISIBLE (-3098 4725);
FORCEPROP 2 LAST ROOM RISER1
J 0
(-3600 4775);
DISPLAY 0.829787 (-3600 4775);
PAINT RED (-3600 4775);
DISPLAY INVISIBLE (-3600 4775);
FORCEADD TAP..6
R 2
(-2950 4575);
FORCEPROP 3 LASTPIN (-3000 4575) SIG_NAME GMI_CPU0_G2_CPU1_G0_TX_DN<12>
J 0
(-2990 4585);
DISPLAY 0.659574 (-2990 4585);
PAINT MONO (-2990 4585);
DISPLAY INVISIBLE (-2990 4585);
FORCEPROP 1 LASTPIN (-3000 4575) BN 12
J 2
(-2948 4583);
DISPLAY 0.489362 (-2948 4583);
PAINT MONO (-2948 4583);
FORCEPROP 2 LAST CDS_LIB standard
J 0
(-2950 4575);
DISPLAY INVISIBLE (-2950 4575);
FORCEPROP 2 LAST BOM_COST IO_SLOT
J 0
(-3450 4675);
DISPLAY 0.829787 (-3450 4675);
DISPLAY INVISIBLE (-3450 4675);
FORCEPROP 1 LAST BODY_TYPE PLUMBING
J 2
(-2950 4525);
DISPLAY 0.702128 (-2950 4525);
PAINT GREEN (-2950 4525);
DISPLAY INVISIBLE (-2950 4525);
FORCEPROP 1 LAST HDL_TAP TRUE
J 2
(-3275 4450);
DISPLAY 0.702128 (-3275 4450);
PAINT GREEN (-3275 4450);
DISPLAY INVISIBLE (-3275 4450);
FORCEPROP 1 LAST PATH I244
J 2
(-2948 4575);
DISPLAY 0.872340 (-2948 4575);
PAINT GREEN (-2948 4575);
DISPLAY INVISIBLE (-2948 4575);
FORCEPROP 2 LAST ROOM RISER1
J 0
(-3450 4625);
DISPLAY 0.829787 (-3450 4625);
PAINT RED (-3450 4625);
DISPLAY INVISIBLE (-3450 4625);
FORCEADD TAP..6
R 2
(-2950 4375);
FORCEPROP 3 LASTPIN (-3000 4375) SIG_NAME GMI_CPU0_G2_CPU1_G0_TX_DN<14>
J 0
(-2990 4385);
DISPLAY 0.659574 (-2990 4385);
PAINT MONO (-2990 4385);
DISPLAY INVISIBLE (-2990 4385);
FORCEPROP 1 LASTPIN (-3000 4375) BN 14
J 2
(-2948 4383);
DISPLAY 0.489362 (-2948 4383);
PAINT MONO (-2948 4383);
FORCEPROP 2 LAST BOM_COST IO_SLOT
J 0
(-3450 4475);
DISPLAY 0.829787 (-3450 4475);
DISPLAY INVISIBLE (-3450 4475);
FORCEPROP 2 LAST CDS_LIB standard
J 0
(-2950 4375);
DISPLAY INVISIBLE (-2950 4375);
FORCEPROP 1 LAST BODY_TYPE PLUMBING
J 2
(-2950 4325);
DISPLAY 0.702128 (-2950 4325);
PAINT GREEN (-2950 4325);
DISPLAY INVISIBLE (-2950 4325);
FORCEPROP 1 LAST HDL_TAP TRUE
J 2
(-3275 4250);
DISPLAY 0.702128 (-3275 4250);
PAINT GREEN (-3275 4250);
DISPLAY INVISIBLE (-3275 4250);
FORCEPROP 1 LAST PATH I245
J 2
(-2948 4375);
DISPLAY 0.872340 (-2948 4375);
PAINT GREEN (-2948 4375);
DISPLAY INVISIBLE (-2948 4375);
FORCEPROP 2 LAST ROOM RISER1
J 0
(-3450 4425);
DISPLAY 0.829787 (-3450 4425);
PAINT RED (-3450 4425);
DISPLAY INVISIBLE (-3450 4425);
FORCEADD TAP..6
R 2
(-2950 4475);
FORCEPROP 3 LASTPIN (-3000 4475) SIG_NAME GMI_CPU0_G2_CPU1_G0_TX_DN<13>
J 0
(-2990 4485);
DISPLAY 0.659574 (-2990 4485);
PAINT MONO (-2990 4485);
DISPLAY INVISIBLE (-2990 4485);
FORCEPROP 1 LASTPIN (-3000 4475) BN 13
J 2
(-2948 4483);
DISPLAY 0.489362 (-2948 4483);
PAINT MONO (-2948 4483);
FORCEPROP 2 LAST CDS_LIB standard
J 0
(-2950 4475);
DISPLAY INVISIBLE (-2950 4475);
FORCEPROP 2 LAST BOM_COST IO_SLOT
J 0
(-3450 4575);
DISPLAY 0.829787 (-3450 4575);
DISPLAY INVISIBLE (-3450 4575);
FORCEPROP 1 LAST BODY_TYPE PLUMBING
J 2
(-2950 4425);
DISPLAY 0.702128 (-2950 4425);
PAINT GREEN (-2950 4425);
DISPLAY INVISIBLE (-2950 4425);
FORCEPROP 1 LAST HDL_TAP TRUE
J 2
(-3275 4350);
DISPLAY 0.702128 (-3275 4350);
PAINT GREEN (-3275 4350);
DISPLAY INVISIBLE (-3275 4350);
FORCEPROP 1 LAST PATH I246
J 2
(-2948 4475);
DISPLAY 0.872340 (-2948 4475);
PAINT GREEN (-2948 4475);
DISPLAY INVISIBLE (-2948 4475);
FORCEPROP 2 LAST ROOM RISER1
J 0
(-3450 4525);
DISPLAY 0.829787 (-3450 4525);
PAINT RED (-3450 4525);
DISPLAY INVISIBLE (-3450 4525);
FORCEADD TAP..6
R 2
(-3100 4425);
FORCEPROP 3 LASTPIN (-3150 4425) SIG_NAME GMI_CPU0_G2_CPU1_G0_TX_DP<14>
J 0
(-3140 4435);
DISPLAY 0.659574 (-3140 4435);
PAINT MONO (-3140 4435);
DISPLAY INVISIBLE (-3140 4435);
FORCEPROP 1 LASTPIN (-3150 4425) BN 14
J 2
(-3098 4433);
DISPLAY 0.489362 (-3098 4433);
PAINT MONO (-3098 4433);
FORCEPROP 2 LAST CDS_LIB standard
J 0
(-3100 4425);
DISPLAY INVISIBLE (-3100 4425);
FORCEPROP 2 LAST BOM_COST IO_SLOT
J 0
(-3600 4525);
DISPLAY 0.829787 (-3600 4525);
DISPLAY INVISIBLE (-3600 4525);
FORCEPROP 1 LAST BODY_TYPE PLUMBING
J 2
(-3100 4375);
DISPLAY 0.702128 (-3100 4375);
PAINT GREEN (-3100 4375);
DISPLAY INVISIBLE (-3100 4375);
FORCEPROP 1 LAST HDL_TAP TRUE
J 2
(-3425 4300);
DISPLAY 0.702128 (-3425 4300);
PAINT GREEN (-3425 4300);
DISPLAY INVISIBLE (-3425 4300);
FORCEPROP 1 LAST PATH I247
J 2
(-3098 4425);
DISPLAY 0.872340 (-3098 4425);
PAINT GREEN (-3098 4425);
DISPLAY INVISIBLE (-3098 4425);
FORCEPROP 2 LAST ROOM RISER1
J 0
(-3600 4475);
DISPLAY 0.829787 (-3600 4475);
PAINT RED (-3600 4475);
DISPLAY INVISIBLE (-3600 4475);
FORCEADD TAP..6
R 2
(-3100 4525);
FORCEPROP 3 LASTPIN (-3150 4525) SIG_NAME GMI_CPU0_G2_CPU1_G0_TX_DP<13>
J 0
(-3140 4535);
DISPLAY 0.659574 (-3140 4535);
PAINT MONO (-3140 4535);
DISPLAY INVISIBLE (-3140 4535);
FORCEPROP 1 LASTPIN (-3150 4525) BN 13
J 2
(-3098 4533);
DISPLAY 0.489362 (-3098 4533);
PAINT MONO (-3098 4533);
FORCEPROP 2 LAST CDS_LIB standard
J 0
(-3100 4525);
DISPLAY INVISIBLE (-3100 4525);
FORCEPROP 2 LAST BOM_COST IO_SLOT
J 0
(-3600 4625);
DISPLAY 0.829787 (-3600 4625);
DISPLAY INVISIBLE (-3600 4625);
FORCEPROP 1 LAST BODY_TYPE PLUMBING
J 2
(-3100 4475);
DISPLAY 0.702128 (-3100 4475);
PAINT GREEN (-3100 4475);
DISPLAY INVISIBLE (-3100 4475);
FORCEPROP 1 LAST HDL_TAP TRUE
J 2
(-3425 4400);
DISPLAY 0.702128 (-3425 4400);
PAINT GREEN (-3425 4400);
DISPLAY INVISIBLE (-3425 4400);
FORCEPROP 1 LAST PATH I248
J 2
(-3098 4525);
DISPLAY 0.872340 (-3098 4525);
PAINT GREEN (-3098 4525);
DISPLAY INVISIBLE (-3098 4525);
FORCEPROP 2 LAST ROOM RISER1
J 0
(-3600 4575);
DISPLAY 0.829787 (-3600 4575);
PAINT RED (-3600 4575);
DISPLAY INVISIBLE (-3600 4575);
FORCEADD TAP..6
R 2
(-2950 4275);
FORCEPROP 3 LASTPIN (-3000 4275) SIG_NAME GMI_CPU0_G2_CPU1_G0_TX_DN<15>
J 0
(-2990 4285);
DISPLAY 0.659574 (-2990 4285);
PAINT MONO (-2990 4285);
DISPLAY INVISIBLE (-2990 4285);
FORCEPROP 1 LASTPIN (-3000 4275) BN 15
J 2
(-2948 4283);
DISPLAY 0.489362 (-2948 4283);
PAINT MONO (-2948 4283);
FORCEPROP 2 LAST CDS_LIB standard
J 0
(-2950 4275);
DISPLAY INVISIBLE (-2950 4275);
FORCEPROP 2 LAST BOM_COST IO_SLOT
J 0
(-3450 4375);
DISPLAY 0.829787 (-3450 4375);
DISPLAY INVISIBLE (-3450 4375);
FORCEPROP 1 LAST BODY_TYPE PLUMBING
J 2
(-2950 4225);
DISPLAY 0.702128 (-2950 4225);
PAINT GREEN (-2950 4225);
DISPLAY INVISIBLE (-2950 4225);
FORCEPROP 1 LAST HDL_TAP TRUE
J 2
(-3275 4150);
DISPLAY 0.702128 (-3275 4150);
PAINT GREEN (-3275 4150);
DISPLAY INVISIBLE (-3275 4150);
FORCEPROP 1 LAST PATH I249
J 2
(-2948 4275);
DISPLAY 0.872340 (-2948 4275);
PAINT GREEN (-2948 4275);
DISPLAY INVISIBLE (-2948 4275);
FORCEPROP 2 LAST ROOM RISER1
J 0
(-3450 4325);
DISPLAY 0.829787 (-3450 4325);
PAINT RED (-3450 4325);
DISPLAY INVISIBLE (-3450 4325);
FORCEADD TAP..6
R 2
(-3100 4325);
FORCEPROP 3 LASTPIN (-3150 4325) SIG_NAME GMI_CPU0_G2_CPU1_G0_TX_DP<15>
J 0
(-3140 4335);
DISPLAY 0.659574 (-3140 4335);
PAINT MONO (-3140 4335);
DISPLAY INVISIBLE (-3140 4335);
FORCEPROP 1 LASTPIN (-3150 4325) BN 15
J 2
(-3098 4333);
DISPLAY 0.489362 (-3098 4333);
PAINT MONO (-3098 4333);
FORCEPROP 2 LAST CDS_LIB standard
J 0
(-3100 4325);
DISPLAY INVISIBLE (-3100 4325);
FORCEPROP 2 LAST BOM_COST IO_SLOT
J 0
(-3600 4425);
DISPLAY 0.829787 (-3600 4425);
DISPLAY INVISIBLE (-3600 4425);
FORCEPROP 1 LAST BODY_TYPE PLUMBING
J 2
(-3100 4275);
DISPLAY 0.702128 (-3100 4275);
PAINT GREEN (-3100 4275);
DISPLAY INVISIBLE (-3100 4275);
FORCEPROP 1 LAST HDL_TAP TRUE
J 2
(-3425 4200);
DISPLAY 0.702128 (-3425 4200);
PAINT GREEN (-3425 4200);
DISPLAY INVISIBLE (-3425 4200);
FORCEPROP 1 LAST PATH I250
J 2
(-3098 4325);
DISPLAY 0.872340 (-3098 4325);
PAINT GREEN (-3098 4325);
DISPLAY INVISIBLE (-3098 4325);
FORCEPROP 2 LAST ROOM RISER1
J 0
(-3600 4375);
DISPLAY 0.829787 (-3600 4375);
PAINT RED (-3600 4375);
DISPLAY INVISIBLE (-3600 4375);
FORCEADD TAP..6
(-6525 5825);
FORCEPROP 3 LASTPIN (-6475 5825) SIG_NAME GMI_CPU1_G0_CPU0_G2_TX_DP<0>
J 0
(-6465 5835);
DISPLAY 0.659574 (-6465 5835);
PAINT MONO (-6465 5835);
DISPLAY INVISIBLE (-6465 5835);
FORCEPROP 1 LASTPIN (-6475 5825) BN 0
J 0
(-6527 5833);
DISPLAY 0.489362 (-6527 5833);
PAINT MONO (-6527 5833);
FORCEPROP 2 LAST CDS_LIB mstr_standard
J 0
(-6525 5825);
DISPLAY INVISIBLE (-6525 5825);
FORCEPROP 1 LAST BODY_TYPE PLUMBING
J 0
(-6525 5775);
DISPLAY 0.574468 (-6525 5775);
PAINT GREEN (-6525 5775);
DISPLAY INVISIBLE (-6525 5775);
FORCEPROP 1 LAST HDL_TAP TRUE
J 0
(-6200 5700);
DISPLAY 0.574468 (-6200 5700);
PAINT GREEN (-6200 5700);
DISPLAY INVISIBLE (-6200 5700);
FORCEPROP 1 LAST PATH I251
J 0
(-6527 5825);
DISPLAY 0.872340 (-6527 5825);
PAINT GREEN (-6527 5825);
DISPLAY INVISIBLE (-6527 5825);
FORCEADD TAP..6
(-6525 5725);
FORCEPROP 3 LASTPIN (-6475 5725) SIG_NAME GMI_CPU1_G0_CPU0_G2_TX_DP<1>
J 0
(-6465 5735);
DISPLAY 0.659574 (-6465 5735);
PAINT MONO (-6465 5735);
DISPLAY INVISIBLE (-6465 5735);
FORCEPROP 1 LASTPIN (-6475 5725) BN 1
J 0
(-6527 5733);
DISPLAY 0.489362 (-6527 5733);
PAINT MONO (-6527 5733);
FORCEPROP 2 LAST CDS_LIB mstr_standard
J 0
(-6525 5725);
DISPLAY INVISIBLE (-6525 5725);
FORCEPROP 1 LAST BODY_TYPE PLUMBING
J 0
(-6525 5675);
DISPLAY 0.574468 (-6525 5675);
PAINT GREEN (-6525 5675);
DISPLAY INVISIBLE (-6525 5675);
FORCEPROP 1 LAST HDL_TAP TRUE
J 0
(-6200 5600);
DISPLAY 0.574468 (-6200 5600);
PAINT GREEN (-6200 5600);
DISPLAY INVISIBLE (-6200 5600);
FORCEPROP 1 LAST PATH I252
J 0
(-6527 5725);
DISPLAY 0.872340 (-6527 5725);
PAINT GREEN (-6527 5725);
DISPLAY INVISIBLE (-6527 5725);
FORCEADD TAP..6
(-6675 5775);
FORCEPROP 3 LASTPIN (-6625 5775) SIG_NAME GMI_CPU1_G0_CPU0_G2_TX_DN<0>
J 0
(-6615 5785);
DISPLAY 0.659574 (-6615 5785);
PAINT MONO (-6615 5785);
DISPLAY INVISIBLE (-6615 5785);
FORCEPROP 1 LASTPIN (-6625 5775) BN 0
J 0
(-6677 5783);
DISPLAY 0.489362 (-6677 5783);
PAINT MONO (-6677 5783);
FORCEPROP 2 LAST CDS_LIB mstr_standard
J 0
(-6675 5775);
DISPLAY INVISIBLE (-6675 5775);
FORCEPROP 1 LAST BODY_TYPE PLUMBING
J 0
(-6675 5725);
DISPLAY 0.574468 (-6675 5725);
PAINT GREEN (-6675 5725);
DISPLAY INVISIBLE (-6675 5725);
FORCEPROP 1 LAST HDL_TAP TRUE
J 0
(-6350 5650);
DISPLAY 0.574468 (-6350 5650);
PAINT GREEN (-6350 5650);
DISPLAY INVISIBLE (-6350 5650);
FORCEPROP 1 LAST PATH I253
J 0
(-6677 5775);
DISPLAY 0.872340 (-6677 5775);
PAINT GREEN (-6677 5775);
DISPLAY INVISIBLE (-6677 5775);
FORCEADD TAP..6
(-6675 5675);
FORCEPROP 3 LASTPIN (-6625 5675) SIG_NAME GMI_CPU1_G0_CPU0_G2_TX_DN<1>
J 0
(-6615 5685);
DISPLAY 0.659574 (-6615 5685);
PAINT MONO (-6615 5685);
DISPLAY INVISIBLE (-6615 5685);
FORCEPROP 1 LASTPIN (-6625 5675) BN 1
J 0
(-6677 5683);
DISPLAY 0.489362 (-6677 5683);
PAINT MONO (-6677 5683);
FORCEPROP 2 LAST CDS_LIB mstr_standard
J 0
(-6675 5675);
DISPLAY INVISIBLE (-6675 5675);
FORCEPROP 1 LAST BODY_TYPE PLUMBING
J 0
(-6675 5625);
DISPLAY 0.574468 (-6675 5625);
PAINT GREEN (-6675 5625);
DISPLAY INVISIBLE (-6675 5625);
FORCEPROP 1 LAST HDL_TAP TRUE
J 0
(-6350 5550);
DISPLAY 0.574468 (-6350 5550);
PAINT GREEN (-6350 5550);
DISPLAY INVISIBLE (-6350 5550);
FORCEPROP 1 LAST PATH I254
J 0
(-6677 5675);
DISPLAY 0.872340 (-6677 5675);
PAINT GREEN (-6677 5675);
DISPLAY INVISIBLE (-6677 5675);
FORCEADD TAP..6
(-6525 5525);
FORCEPROP 3 LASTPIN (-6475 5525) SIG_NAME GMI_CPU1_G0_CPU0_G2_TX_DP<3>
J 0
(-6465 5535);
DISPLAY 0.659574 (-6465 5535);
PAINT MONO (-6465 5535);
DISPLAY INVISIBLE (-6465 5535);
FORCEPROP 1 LASTPIN (-6475 5525) BN 3
J 0
(-6527 5533);
DISPLAY 0.489362 (-6527 5533);
PAINT MONO (-6527 5533);
FORCEPROP 2 LAST CDS_LIB standard
J 0
(-6525 5525);
DISPLAY INVISIBLE (-6525 5525);
FORCEPROP 1 LAST BODY_TYPE PLUMBING
J 0
(-6525 5475);
DISPLAY 0.574468 (-6525 5475);
PAINT GREEN (-6525 5475);
DISPLAY INVISIBLE (-6525 5475);
FORCEPROP 1 LAST HDL_TAP TRUE
J 0
(-6200 5400);
DISPLAY 0.574468 (-6200 5400);
PAINT GREEN (-6200 5400);
DISPLAY INVISIBLE (-6200 5400);
FORCEPROP 1 LAST PATH I255
J 0
(-6527 5525);
DISPLAY 0.872340 (-6527 5525);
PAINT GREEN (-6527 5525);
DISPLAY INVISIBLE (-6527 5525);
FORCEADD TAP..6
(-6525 5625);
FORCEPROP 3 LASTPIN (-6475 5625) SIG_NAME GMI_CPU1_G0_CPU0_G2_TX_DP<2>
J 0
(-6465 5635);
DISPLAY 0.659574 (-6465 5635);
PAINT MONO (-6465 5635);
DISPLAY INVISIBLE (-6465 5635);
FORCEPROP 1 LASTPIN (-6475 5625) BN 2
J 0
(-6527 5633);
DISPLAY 0.489362 (-6527 5633);
PAINT MONO (-6527 5633);
FORCEPROP 2 LAST CDS_LIB mstr_standard
J 0
(-6525 5625);
DISPLAY INVISIBLE (-6525 5625);
FORCEPROP 1 LAST BODY_TYPE PLUMBING
J 0
(-6525 5575);
DISPLAY 0.574468 (-6525 5575);
PAINT GREEN (-6525 5575);
DISPLAY INVISIBLE (-6525 5575);
FORCEPROP 1 LAST HDL_TAP TRUE
J 0
(-6200 5500);
DISPLAY 0.574468 (-6200 5500);
PAINT GREEN (-6200 5500);
DISPLAY INVISIBLE (-6200 5500);
FORCEPROP 1 LAST PATH I256
J 0
(-6527 5625);
DISPLAY 0.872340 (-6527 5625);
PAINT GREEN (-6527 5625);
DISPLAY INVISIBLE (-6527 5625);
FORCEADD TAP..6
(-6525 5425);
FORCEPROP 3 LASTPIN (-6475 5425) SIG_NAME GMI_CPU1_G0_CPU0_G2_TX_DP<4>
J 0
(-6465 5435);
DISPLAY 0.659574 (-6465 5435);
PAINT MONO (-6465 5435);
DISPLAY INVISIBLE (-6465 5435);
FORCEPROP 1 LASTPIN (-6475 5425) BN 4
J 0
(-6527 5433);
DISPLAY 0.489362 (-6527 5433);
PAINT MONO (-6527 5433);
FORCEPROP 2 LAST CDS_LIB standard
J 0
(-6525 5425);
DISPLAY INVISIBLE (-6525 5425);
FORCEPROP 1 LAST BODY_TYPE PLUMBING
J 0
(-6525 5375);
DISPLAY 0.574468 (-6525 5375);
PAINT GREEN (-6525 5375);
DISPLAY INVISIBLE (-6525 5375);
FORCEPROP 1 LAST HDL_TAP TRUE
J 0
(-6200 5300);
DISPLAY 0.574468 (-6200 5300);
PAINT GREEN (-6200 5300);
DISPLAY INVISIBLE (-6200 5300);
FORCEPROP 1 LAST PATH I257
J 0
(-6527 5425);
DISPLAY 0.872340 (-6527 5425);
PAINT GREEN (-6527 5425);
DISPLAY INVISIBLE (-6527 5425);
FORCEADD TAP..6
(-6675 5575);
FORCEPROP 3 LASTPIN (-6625 5575) SIG_NAME GMI_CPU1_G0_CPU0_G2_TX_DN<2>
J 0
(-6615 5585);
DISPLAY 0.659574 (-6615 5585);
PAINT MONO (-6615 5585);
DISPLAY INVISIBLE (-6615 5585);
FORCEPROP 1 LASTPIN (-6625 5575) BN 2
J 0
(-6677 5583);
DISPLAY 0.489362 (-6677 5583);
PAINT MONO (-6677 5583);
FORCEPROP 2 LAST CDS_LIB standard
J 0
(-6675 5575);
DISPLAY INVISIBLE (-6675 5575);
FORCEPROP 1 LAST BODY_TYPE PLUMBING
J 0
(-6675 5525);
DISPLAY 0.574468 (-6675 5525);
PAINT GREEN (-6675 5525);
DISPLAY INVISIBLE (-6675 5525);
FORCEPROP 1 LAST HDL_TAP TRUE
J 0
(-6350 5450);
DISPLAY 0.574468 (-6350 5450);
PAINT GREEN (-6350 5450);
DISPLAY INVISIBLE (-6350 5450);
FORCEPROP 1 LAST PATH I258
J 0
(-6677 5575);
DISPLAY 0.872340 (-6677 5575);
PAINT GREEN (-6677 5575);
DISPLAY INVISIBLE (-6677 5575);
FORCEADD TAP..6
(-6675 5475);
FORCEPROP 3 LASTPIN (-6625 5475) SIG_NAME GMI_CPU1_G0_CPU0_G2_TX_DN<3>
J 0
(-6615 5485);
DISPLAY 0.659574 (-6615 5485);
PAINT MONO (-6615 5485);
DISPLAY INVISIBLE (-6615 5485);
FORCEPROP 1 LASTPIN (-6625 5475) BN 3
J 0
(-6677 5483);
DISPLAY 0.489362 (-6677 5483);
PAINT MONO (-6677 5483);
FORCEPROP 2 LAST CDS_LIB standard
J 0
(-6675 5475);
DISPLAY INVISIBLE (-6675 5475);
FORCEPROP 1 LAST BODY_TYPE PLUMBING
J 0
(-6675 5425);
DISPLAY 0.574468 (-6675 5425);
PAINT GREEN (-6675 5425);
DISPLAY INVISIBLE (-6675 5425);
FORCEPROP 1 LAST HDL_TAP TRUE
J 0
(-6350 5350);
DISPLAY 0.574468 (-6350 5350);
PAINT GREEN (-6350 5350);
DISPLAY INVISIBLE (-6350 5350);
FORCEPROP 1 LAST PATH I259
J 0
(-6677 5475);
DISPLAY 0.872340 (-6677 5475);
PAINT GREEN (-6677 5475);
DISPLAY INVISIBLE (-6677 5475);
FORCEADD TAP..6
(-6525 5325);
FORCEPROP 3 LASTPIN (-6475 5325) SIG_NAME GMI_CPU1_G0_CPU0_G2_TX_DP<5>
J 0
(-6465 5335);
DISPLAY 0.659574 (-6465 5335);
PAINT MONO (-6465 5335);
DISPLAY INVISIBLE (-6465 5335);
FORCEPROP 1 LASTPIN (-6475 5325) BN 5
J 0
(-6527 5333);
DISPLAY 0.489362 (-6527 5333);
PAINT MONO (-6527 5333);
FORCEPROP 2 LAST CDS_LIB standard
J 0
(-6525 5325);
DISPLAY INVISIBLE (-6525 5325);
FORCEPROP 1 LAST BODY_TYPE PLUMBING
J 0
(-6525 5275);
DISPLAY 0.574468 (-6525 5275);
PAINT GREEN (-6525 5275);
DISPLAY INVISIBLE (-6525 5275);
FORCEPROP 1 LAST HDL_TAP TRUE
J 0
(-6200 5200);
DISPLAY 0.574468 (-6200 5200);
PAINT GREEN (-6200 5200);
DISPLAY INVISIBLE (-6200 5200);
FORCEPROP 1 LAST PATH I260
J 0
(-6527 5325);
DISPLAY 0.872340 (-6527 5325);
PAINT GREEN (-6527 5325);
DISPLAY INVISIBLE (-6527 5325);
FORCEADD TAP..6
(-6525 5225);
FORCEPROP 3 LASTPIN (-6475 5225) SIG_NAME GMI_CPU1_G0_CPU0_G2_TX_DP<6>
J 0
(-6465 5235);
DISPLAY 0.659574 (-6465 5235);
PAINT MONO (-6465 5235);
DISPLAY INVISIBLE (-6465 5235);
FORCEPROP 1 LASTPIN (-6475 5225) BN 6
J 0
(-6527 5233);
DISPLAY 0.489362 (-6527 5233);
PAINT MONO (-6527 5233);
FORCEPROP 2 LAST CDS_LIB standard
J 0
(-6525 5225);
DISPLAY INVISIBLE (-6525 5225);
FORCEPROP 1 LAST BODY_TYPE PLUMBING
J 0
(-6525 5175);
DISPLAY 0.574468 (-6525 5175);
PAINT GREEN (-6525 5175);
DISPLAY INVISIBLE (-6525 5175);
FORCEPROP 1 LAST HDL_TAP TRUE
J 0
(-6200 5100);
DISPLAY 0.574468 (-6200 5100);
PAINT GREEN (-6200 5100);
DISPLAY INVISIBLE (-6200 5100);
FORCEPROP 1 LAST PATH I261
J 0
(-6527 5225);
DISPLAY 0.872340 (-6527 5225);
PAINT GREEN (-6527 5225);
DISPLAY INVISIBLE (-6527 5225);
FORCEADD TAP..6
(-6525 5125);
FORCEPROP 3 LASTPIN (-6475 5125) SIG_NAME GMI_CPU1_G0_CPU0_G2_TX_DP<7>
J 0
(-6465 5135);
DISPLAY 0.659574 (-6465 5135);
PAINT MONO (-6465 5135);
DISPLAY INVISIBLE (-6465 5135);
FORCEPROP 1 LASTPIN (-6475 5125) BN 7
J 0
(-6527 5133);
DISPLAY 0.489362 (-6527 5133);
PAINT MONO (-6527 5133);
FORCEPROP 2 LAST CDS_LIB standard
J 0
(-6525 5125);
DISPLAY INVISIBLE (-6525 5125);
FORCEPROP 1 LAST BODY_TYPE PLUMBING
J 0
(-6525 5075);
DISPLAY 0.574468 (-6525 5075);
PAINT GREEN (-6525 5075);
DISPLAY INVISIBLE (-6525 5075);
FORCEPROP 1 LAST HDL_TAP TRUE
J 0
(-6200 5000);
DISPLAY 0.574468 (-6200 5000);
PAINT GREEN (-6200 5000);
DISPLAY INVISIBLE (-6200 5000);
FORCEPROP 1 LAST PATH I262
J 0
(-6527 5125);
DISPLAY 0.872340 (-6527 5125);
PAINT GREEN (-6527 5125);
DISPLAY INVISIBLE (-6527 5125);
FORCEADD TAP..6
(-6675 5275);
FORCEPROP 3 LASTPIN (-6625 5275) SIG_NAME GMI_CPU1_G0_CPU0_G2_TX_DN<5>
J 0
(-6615 5285);
DISPLAY 0.659574 (-6615 5285);
PAINT MONO (-6615 5285);
DISPLAY INVISIBLE (-6615 5285);
FORCEPROP 1 LASTPIN (-6625 5275) BN 5
J 0
(-6677 5283);
DISPLAY 0.489362 (-6677 5283);
PAINT MONO (-6677 5283);
FORCEPROP 2 LAST CDS_LIB standard
J 0
(-6675 5275);
DISPLAY INVISIBLE (-6675 5275);
FORCEPROP 1 LAST BODY_TYPE PLUMBING
J 0
(-6675 5225);
DISPLAY 0.574468 (-6675 5225);
PAINT GREEN (-6675 5225);
DISPLAY INVISIBLE (-6675 5225);
FORCEPROP 1 LAST HDL_TAP TRUE
J 0
(-6350 5150);
DISPLAY 0.574468 (-6350 5150);
PAINT GREEN (-6350 5150);
DISPLAY INVISIBLE (-6350 5150);
FORCEPROP 1 LAST PATH I263
J 0
(-6677 5275);
DISPLAY 0.872340 (-6677 5275);
PAINT GREEN (-6677 5275);
DISPLAY INVISIBLE (-6677 5275);
FORCEADD TAP..6
(-6675 5375);
FORCEPROP 3 LASTPIN (-6625 5375) SIG_NAME GMI_CPU1_G0_CPU0_G2_TX_DN<4>
J 0
(-6615 5385);
DISPLAY 0.659574 (-6615 5385);
PAINT MONO (-6615 5385);
DISPLAY INVISIBLE (-6615 5385);
FORCEPROP 1 LASTPIN (-6625 5375) BN 4
J 0
(-6677 5383);
DISPLAY 0.489362 (-6677 5383);
PAINT MONO (-6677 5383);
FORCEPROP 2 LAST CDS_LIB standard
J 0
(-6675 5375);
DISPLAY INVISIBLE (-6675 5375);
FORCEPROP 1 LAST BODY_TYPE PLUMBING
J 0
(-6675 5325);
DISPLAY 0.574468 (-6675 5325);
PAINT GREEN (-6675 5325);
DISPLAY INVISIBLE (-6675 5325);
FORCEPROP 1 LAST HDL_TAP TRUE
J 0
(-6350 5250);
DISPLAY 0.574468 (-6350 5250);
PAINT GREEN (-6350 5250);
DISPLAY INVISIBLE (-6350 5250);
FORCEPROP 1 LAST PATH I264
J 0
(-6677 5375);
DISPLAY 0.872340 (-6677 5375);
PAINT GREEN (-6677 5375);
DISPLAY INVISIBLE (-6677 5375);
FORCEADD TAP..6
(-6675 5175);
FORCEPROP 3 LASTPIN (-6625 5175) SIG_NAME GMI_CPU1_G0_CPU0_G2_TX_DN<6>
J 0
(-6615 5185);
DISPLAY 0.659574 (-6615 5185);
PAINT MONO (-6615 5185);
DISPLAY INVISIBLE (-6615 5185);
FORCEPROP 1 LASTPIN (-6625 5175) BN 6
J 0
(-6677 5183);
DISPLAY 0.489362 (-6677 5183);
PAINT MONO (-6677 5183);
FORCEPROP 2 LAST CDS_LIB standard
J 0
(-6675 5175);
DISPLAY INVISIBLE (-6675 5175);
FORCEPROP 1 LAST BODY_TYPE PLUMBING
J 0
(-6675 5125);
DISPLAY 0.574468 (-6675 5125);
PAINT GREEN (-6675 5125);
DISPLAY INVISIBLE (-6675 5125);
FORCEPROP 1 LAST HDL_TAP TRUE
J 0
(-6350 5050);
DISPLAY 0.574468 (-6350 5050);
PAINT GREEN (-6350 5050);
DISPLAY INVISIBLE (-6350 5050);
FORCEPROP 1 LAST PATH I265
J 0
(-6677 5175);
DISPLAY 0.872340 (-6677 5175);
PAINT GREEN (-6677 5175);
DISPLAY INVISIBLE (-6677 5175);
FORCEADD TAP..6
(-6525 5025);
FORCEPROP 3 LASTPIN (-6475 5025) SIG_NAME GMI_CPU1_G0_CPU0_G2_TX_DP<8>
J 0
(-6465 5035);
DISPLAY 0.659574 (-6465 5035);
PAINT MONO (-6465 5035);
DISPLAY INVISIBLE (-6465 5035);
FORCEPROP 1 LASTPIN (-6475 5025) BN 8
J 0
(-6527 5033);
DISPLAY 0.489362 (-6527 5033);
PAINT MONO (-6527 5033);
FORCEPROP 2 LAST CDS_LIB standard
J 0
(-6525 5025);
DISPLAY INVISIBLE (-6525 5025);
FORCEPROP 1 LAST BODY_TYPE PLUMBING
J 0
(-6525 4975);
DISPLAY 0.574468 (-6525 4975);
PAINT GREEN (-6525 4975);
DISPLAY INVISIBLE (-6525 4975);
FORCEPROP 1 LAST HDL_TAP TRUE
J 0
(-6200 4900);
DISPLAY 0.574468 (-6200 4900);
PAINT GREEN (-6200 4900);
DISPLAY INVISIBLE (-6200 4900);
FORCEPROP 1 LAST PATH I266
J 0
(-6527 5025);
DISPLAY 0.872340 (-6527 5025);
PAINT GREEN (-6527 5025);
DISPLAY INVISIBLE (-6527 5025);
FORCEADD TAP..6
(-6525 4925);
FORCEPROP 3 LASTPIN (-6475 4925) SIG_NAME GMI_CPU1_G0_CPU0_G2_TX_DP<9>
J 0
(-6465 4935);
DISPLAY 0.659574 (-6465 4935);
PAINT MONO (-6465 4935);
DISPLAY INVISIBLE (-6465 4935);
FORCEPROP 1 LASTPIN (-6475 4925) BN 9
J 0
(-6527 4933);
DISPLAY 0.489362 (-6527 4933);
PAINT MONO (-6527 4933);
FORCEPROP 2 LAST CDS_LIB standard
J 0
(-6525 4925);
DISPLAY INVISIBLE (-6525 4925);
FORCEPROP 1 LAST BODY_TYPE PLUMBING
J 0
(-6525 4875);
DISPLAY 0.574468 (-6525 4875);
PAINT GREEN (-6525 4875);
DISPLAY INVISIBLE (-6525 4875);
FORCEPROP 1 LAST HDL_TAP TRUE
J 0
(-6200 4800);
DISPLAY 0.574468 (-6200 4800);
PAINT GREEN (-6200 4800);
DISPLAY INVISIBLE (-6200 4800);
FORCEPROP 1 LAST PATH I267
J 0
(-6527 4925);
DISPLAY 0.872340 (-6527 4925);
PAINT GREEN (-6527 4925);
DISPLAY INVISIBLE (-6527 4925);
FORCEADD TAP..6
(-6675 5075);
FORCEPROP 3 LASTPIN (-6625 5075) SIG_NAME GMI_CPU1_G0_CPU0_G2_TX_DN<7>
J 0
(-6615 5085);
DISPLAY 0.659574 (-6615 5085);
PAINT MONO (-6615 5085);
DISPLAY INVISIBLE (-6615 5085);
FORCEPROP 1 LASTPIN (-6625 5075) BN 7
J 0
(-6677 5083);
DISPLAY 0.489362 (-6677 5083);
PAINT MONO (-6677 5083);
FORCEPROP 2 LAST CDS_LIB standard
J 0
(-6675 5075);
DISPLAY INVISIBLE (-6675 5075);
FORCEPROP 1 LAST BODY_TYPE PLUMBING
J 0
(-6675 5025);
DISPLAY 0.574468 (-6675 5025);
PAINT GREEN (-6675 5025);
DISPLAY INVISIBLE (-6675 5025);
FORCEPROP 1 LAST HDL_TAP TRUE
J 0
(-6350 4950);
DISPLAY 0.574468 (-6350 4950);
PAINT GREEN (-6350 4950);
DISPLAY INVISIBLE (-6350 4950);
FORCEPROP 1 LAST PATH I268
J 0
(-6677 5075);
DISPLAY 0.872340 (-6677 5075);
PAINT GREEN (-6677 5075);
DISPLAY INVISIBLE (-6677 5075);
FORCEADD TAP..6
(-6675 4975);
FORCEPROP 3 LASTPIN (-6625 4975) SIG_NAME GMI_CPU1_G0_CPU0_G2_TX_DN<8>
J 0
(-6615 4985);
DISPLAY 0.659574 (-6615 4985);
PAINT MONO (-6615 4985);
DISPLAY INVISIBLE (-6615 4985);
FORCEPROP 1 LASTPIN (-6625 4975) BN 8
J 0
(-6677 4983);
DISPLAY 0.489362 (-6677 4983);
PAINT MONO (-6677 4983);
FORCEPROP 2 LAST CDS_LIB standard
J 0
(-6675 4975);
DISPLAY INVISIBLE (-6675 4975);
FORCEPROP 1 LAST BODY_TYPE PLUMBING
J 0
(-6675 4925);
DISPLAY 0.574468 (-6675 4925);
PAINT GREEN (-6675 4925);
DISPLAY INVISIBLE (-6675 4925);
FORCEPROP 1 LAST HDL_TAP TRUE
J 0
(-6350 4850);
DISPLAY 0.574468 (-6350 4850);
PAINT GREEN (-6350 4850);
DISPLAY INVISIBLE (-6350 4850);
FORCEPROP 1 LAST PATH I269
J 0
(-6677 4975);
DISPLAY 0.872340 (-6677 4975);
PAINT GREEN (-6677 4975);
DISPLAY INVISIBLE (-6677 4975);
FORCEADD TAP..6
(-6675 4875);
FORCEPROP 3 LASTPIN (-6625 4875) SIG_NAME GMI_CPU1_G0_CPU0_G2_TX_DN<9>
J 0
(-6615 4885);
DISPLAY 0.659574 (-6615 4885);
PAINT MONO (-6615 4885);
DISPLAY INVISIBLE (-6615 4885);
FORCEPROP 1 LASTPIN (-6625 4875) BN 9
J 0
(-6677 4883);
DISPLAY 0.489362 (-6677 4883);
PAINT MONO (-6677 4883);
FORCEPROP 2 LAST CDS_LIB standard
J 0
(-6675 4875);
DISPLAY INVISIBLE (-6675 4875);
FORCEPROP 1 LAST BODY_TYPE PLUMBING
J 0
(-6675 4825);
DISPLAY 0.574468 (-6675 4825);
PAINT GREEN (-6675 4825);
DISPLAY INVISIBLE (-6675 4825);
FORCEPROP 1 LAST HDL_TAP TRUE
J 0
(-6350 4750);
DISPLAY 0.574468 (-6350 4750);
PAINT GREEN (-6350 4750);
DISPLAY INVISIBLE (-6350 4750);
FORCEPROP 1 LAST PATH I270
J 0
(-6677 4875);
DISPLAY 0.872340 (-6677 4875);
PAINT GREEN (-6677 4875);
DISPLAY INVISIBLE (-6677 4875);
FORCEADD TAP..6
(-6525 4825);
FORCEPROP 3 LASTPIN (-6475 4825) SIG_NAME GMI_CPU1_G0_CPU0_G2_TX_DP<10>
J 0
(-6465 4835);
DISPLAY 0.659574 (-6465 4835);
PAINT MONO (-6465 4835);
DISPLAY INVISIBLE (-6465 4835);
FORCEPROP 1 LASTPIN (-6475 4825) BN 10
J 0
(-6527 4833);
DISPLAY 0.489362 (-6527 4833);
PAINT MONO (-6527 4833);
FORCEPROP 2 LAST CDS_LIB standard
J 0
(-6525 4825);
DISPLAY INVISIBLE (-6525 4825);
FORCEPROP 1 LAST BODY_TYPE PLUMBING
J 0
(-6525 4775);
DISPLAY 0.574468 (-6525 4775);
PAINT GREEN (-6525 4775);
DISPLAY INVISIBLE (-6525 4775);
FORCEPROP 1 LAST HDL_TAP TRUE
J 0
(-6200 4700);
DISPLAY 0.574468 (-6200 4700);
PAINT GREEN (-6200 4700);
DISPLAY INVISIBLE (-6200 4700);
FORCEPROP 1 LAST PATH I271
J 0
(-6527 4825);
DISPLAY 0.872340 (-6527 4825);
PAINT GREEN (-6527 4825);
DISPLAY INVISIBLE (-6527 4825);
FORCEADD TAP..6
(-6525 4625);
FORCEPROP 3 LASTPIN (-6475 4625) SIG_NAME GMI_CPU1_G0_CPU0_G2_TX_DP<12>
J 0
(-6465 4635);
DISPLAY 0.659574 (-6465 4635);
PAINT MONO (-6465 4635);
DISPLAY INVISIBLE (-6465 4635);
FORCEPROP 1 LASTPIN (-6475 4625) BN 12
J 0
(-6527 4633);
DISPLAY 0.489362 (-6527 4633);
PAINT MONO (-6527 4633);
FORCEPROP 2 LAST CDS_LIB standard
J 0
(-6525 4625);
DISPLAY INVISIBLE (-6525 4625);
FORCEPROP 1 LAST BODY_TYPE PLUMBING
J 0
(-6525 4575);
DISPLAY 0.574468 (-6525 4575);
PAINT GREEN (-6525 4575);
DISPLAY INVISIBLE (-6525 4575);
FORCEPROP 1 LAST HDL_TAP TRUE
J 0
(-6200 4500);
DISPLAY 0.574468 (-6200 4500);
PAINT GREEN (-6200 4500);
DISPLAY INVISIBLE (-6200 4500);
FORCEPROP 1 LAST PATH I272
J 0
(-6527 4625);
DISPLAY 0.872340 (-6527 4625);
PAINT GREEN (-6527 4625);
DISPLAY INVISIBLE (-6527 4625);
FORCEADD TAP..6
(-6525 4725);
FORCEPROP 3 LASTPIN (-6475 4725) SIG_NAME GMI_CPU1_G0_CPU0_G2_TX_DP<11>
J 0
(-6465 4735);
DISPLAY 0.659574 (-6465 4735);
PAINT MONO (-6465 4735);
DISPLAY INVISIBLE (-6465 4735);
FORCEPROP 1 LASTPIN (-6475 4725) BN 11
J 0
(-6527 4733);
DISPLAY 0.489362 (-6527 4733);
PAINT MONO (-6527 4733);
FORCEPROP 2 LAST CDS_LIB standard
J 0
(-6525 4725);
DISPLAY INVISIBLE (-6525 4725);
FORCEPROP 1 LAST BODY_TYPE PLUMBING
J 0
(-6525 4675);
DISPLAY 0.574468 (-6525 4675);
PAINT GREEN (-6525 4675);
DISPLAY INVISIBLE (-6525 4675);
FORCEPROP 1 LAST HDL_TAP TRUE
J 0
(-6200 4600);
DISPLAY 0.574468 (-6200 4600);
PAINT GREEN (-6200 4600);
DISPLAY INVISIBLE (-6200 4600);
FORCEPROP 1 LAST PATH I273
J 0
(-6527 4725);
DISPLAY 0.872340 (-6527 4725);
PAINT GREEN (-6527 4725);
DISPLAY INVISIBLE (-6527 4725);
FORCEADD TAP..6
(-6675 4775);
FORCEPROP 3 LASTPIN (-6625 4775) SIG_NAME GMI_CPU1_G0_CPU0_G2_TX_DN<10>
J 0
(-6615 4785);
DISPLAY 0.659574 (-6615 4785);
PAINT MONO (-6615 4785);
DISPLAY INVISIBLE (-6615 4785);
FORCEPROP 1 LASTPIN (-6625 4775) BN 10
J 0
(-6677 4783);
DISPLAY 0.489362 (-6677 4783);
PAINT MONO (-6677 4783);
FORCEPROP 2 LAST CDS_LIB standard
J 0
(-6675 4775);
DISPLAY INVISIBLE (-6675 4775);
FORCEPROP 1 LAST BODY_TYPE PLUMBING
J 0
(-6675 4725);
DISPLAY 0.574468 (-6675 4725);
PAINT GREEN (-6675 4725);
DISPLAY INVISIBLE (-6675 4725);
FORCEPROP 1 LAST HDL_TAP TRUE
J 0
(-6350 4650);
DISPLAY 0.574468 (-6350 4650);
PAINT GREEN (-6350 4650);
DISPLAY INVISIBLE (-6350 4650);
FORCEPROP 1 LAST PATH I274
J 0
(-6677 4775);
DISPLAY 0.872340 (-6677 4775);
PAINT GREEN (-6677 4775);
DISPLAY INVISIBLE (-6677 4775);
FORCEADD TAP..6
(-6675 4675);
FORCEPROP 3 LASTPIN (-6625 4675) SIG_NAME GMI_CPU1_G0_CPU0_G2_TX_DN<11>
J 0
(-6615 4685);
DISPLAY 0.659574 (-6615 4685);
PAINT MONO (-6615 4685);
DISPLAY INVISIBLE (-6615 4685);
FORCEPROP 1 LASTPIN (-6625 4675) BN 11
J 0
(-6677 4683);
DISPLAY 0.489362 (-6677 4683);
PAINT MONO (-6677 4683);
FORCEPROP 2 LAST CDS_LIB standard
J 0
(-6675 4675);
DISPLAY INVISIBLE (-6675 4675);
FORCEPROP 1 LAST BODY_TYPE PLUMBING
J 0
(-6675 4625);
DISPLAY 0.574468 (-6675 4625);
PAINT GREEN (-6675 4625);
DISPLAY INVISIBLE (-6675 4625);
FORCEPROP 1 LAST HDL_TAP TRUE
J 0
(-6350 4550);
DISPLAY 0.574468 (-6350 4550);
PAINT GREEN (-6350 4550);
DISPLAY INVISIBLE (-6350 4550);
FORCEPROP 1 LAST PATH I275
J 0
(-6677 4675);
DISPLAY 0.872340 (-6677 4675);
PAINT GREEN (-6677 4675);
DISPLAY INVISIBLE (-6677 4675);
FORCEADD TAP..6
(-6525 4525);
FORCEPROP 3 LASTPIN (-6475 4525) SIG_NAME GMI_CPU1_G0_CPU0_G2_TX_DP<13>
J 0
(-6465 4535);
DISPLAY 0.659574 (-6465 4535);
PAINT MONO (-6465 4535);
DISPLAY INVISIBLE (-6465 4535);
FORCEPROP 1 LASTPIN (-6475 4525) BN 13
J 0
(-6527 4533);
DISPLAY 0.489362 (-6527 4533);
PAINT MONO (-6527 4533);
FORCEPROP 2 LAST CDS_LIB standard
J 0
(-6525 4525);
DISPLAY INVISIBLE (-6525 4525);
FORCEPROP 1 LAST BODY_TYPE PLUMBING
J 0
(-6525 4475);
DISPLAY 0.574468 (-6525 4475);
PAINT GREEN (-6525 4475);
DISPLAY INVISIBLE (-6525 4475);
FORCEPROP 1 LAST HDL_TAP TRUE
J 0
(-6200 4400);
DISPLAY 0.574468 (-6200 4400);
PAINT GREEN (-6200 4400);
DISPLAY INVISIBLE (-6200 4400);
FORCEPROP 1 LAST PATH I276
J 0
(-6527 4525);
DISPLAY 0.872340 (-6527 4525);
PAINT GREEN (-6527 4525);
DISPLAY INVISIBLE (-6527 4525);
FORCEADD TAP..6
(-6525 4425);
FORCEPROP 3 LASTPIN (-6475 4425) SIG_NAME GMI_CPU1_G0_CPU0_G2_TX_DP<14>
J 0
(-6465 4435);
DISPLAY 0.659574 (-6465 4435);
PAINT MONO (-6465 4435);
DISPLAY INVISIBLE (-6465 4435);
FORCEPROP 1 LASTPIN (-6475 4425) BN 14
J 0
(-6527 4433);
DISPLAY 0.489362 (-6527 4433);
PAINT MONO (-6527 4433);
FORCEPROP 2 LAST CDS_LIB standard
J 0
(-6525 4425);
DISPLAY INVISIBLE (-6525 4425);
FORCEPROP 1 LAST BODY_TYPE PLUMBING
J 0
(-6525 4375);
DISPLAY 0.574468 (-6525 4375);
PAINT GREEN (-6525 4375);
DISPLAY INVISIBLE (-6525 4375);
FORCEPROP 1 LAST HDL_TAP TRUE
J 0
(-6200 4300);
DISPLAY 0.574468 (-6200 4300);
PAINT GREEN (-6200 4300);
DISPLAY INVISIBLE (-6200 4300);
FORCEPROP 1 LAST PATH I277
J 0
(-6527 4425);
DISPLAY 0.872340 (-6527 4425);
PAINT GREEN (-6527 4425);
DISPLAY INVISIBLE (-6527 4425);
FORCEADD TAP..6
(-6675 4575);
FORCEPROP 3 LASTPIN (-6625 4575) SIG_NAME GMI_CPU1_G0_CPU0_G2_TX_DN<12>
J 0
(-6615 4585);
DISPLAY 0.659574 (-6615 4585);
PAINT MONO (-6615 4585);
DISPLAY INVISIBLE (-6615 4585);
FORCEPROP 1 LASTPIN (-6625 4575) BN 12
J 0
(-6677 4583);
DISPLAY 0.489362 (-6677 4583);
PAINT MONO (-6677 4583);
FORCEPROP 2 LAST CDS_LIB standard
J 0
(-6675 4575);
DISPLAY INVISIBLE (-6675 4575);
FORCEPROP 1 LAST BODY_TYPE PLUMBING
J 0
(-6675 4525);
DISPLAY 0.574468 (-6675 4525);
PAINT GREEN (-6675 4525);
DISPLAY INVISIBLE (-6675 4525);
FORCEPROP 1 LAST HDL_TAP TRUE
J 0
(-6350 4450);
DISPLAY 0.574468 (-6350 4450);
PAINT GREEN (-6350 4450);
DISPLAY INVISIBLE (-6350 4450);
FORCEPROP 1 LAST PATH I278
J 0
(-6677 4575);
DISPLAY 0.872340 (-6677 4575);
PAINT GREEN (-6677 4575);
DISPLAY INVISIBLE (-6677 4575);
FORCEADD TAP..6
(-6675 4475);
FORCEPROP 3 LASTPIN (-6625 4475) SIG_NAME GMI_CPU1_G0_CPU0_G2_TX_DN<13>
J 0
(-6615 4485);
DISPLAY 0.659574 (-6615 4485);
PAINT MONO (-6615 4485);
DISPLAY INVISIBLE (-6615 4485);
FORCEPROP 1 LASTPIN (-6625 4475) BN 13
J 0
(-6677 4483);
DISPLAY 0.489362 (-6677 4483);
PAINT MONO (-6677 4483);
FORCEPROP 2 LAST CDS_LIB standard
J 0
(-6675 4475);
DISPLAY INVISIBLE (-6675 4475);
FORCEPROP 1 LAST BODY_TYPE PLUMBING
J 0
(-6675 4425);
DISPLAY 0.574468 (-6675 4425);
PAINT GREEN (-6675 4425);
DISPLAY INVISIBLE (-6675 4425);
FORCEPROP 1 LAST HDL_TAP TRUE
J 0
(-6350 4350);
DISPLAY 0.574468 (-6350 4350);
PAINT GREEN (-6350 4350);
DISPLAY INVISIBLE (-6350 4350);
FORCEPROP 1 LAST PATH I279
J 0
(-6677 4475);
DISPLAY 0.872340 (-6677 4475);
PAINT GREEN (-6677 4475);
DISPLAY INVISIBLE (-6677 4475);
FORCEADD TAP..6
(-6675 4375);
FORCEPROP 3 LASTPIN (-6625 4375) SIG_NAME GMI_CPU1_G0_CPU0_G2_TX_DN<14>
J 0
(-6615 4385);
DISPLAY 0.659574 (-6615 4385);
PAINT MONO (-6615 4385);
DISPLAY INVISIBLE (-6615 4385);
FORCEPROP 1 LASTPIN (-6625 4375) BN 14
J 0
(-6677 4383);
DISPLAY 0.489362 (-6677 4383);
PAINT MONO (-6677 4383);
FORCEPROP 2 LAST CDS_LIB standard
J 0
(-6675 4375);
DISPLAY INVISIBLE (-6675 4375);
FORCEPROP 1 LAST BODY_TYPE PLUMBING
J 0
(-6675 4325);
DISPLAY 0.574468 (-6675 4325);
PAINT GREEN (-6675 4325);
DISPLAY INVISIBLE (-6675 4325);
FORCEPROP 1 LAST HDL_TAP TRUE
J 0
(-6350 4250);
DISPLAY 0.574468 (-6350 4250);
PAINT GREEN (-6350 4250);
DISPLAY INVISIBLE (-6350 4250);
FORCEPROP 1 LAST PATH I280
J 0
(-6677 4375);
DISPLAY 0.872340 (-6677 4375);
PAINT GREEN (-6677 4375);
DISPLAY INVISIBLE (-6677 4375);
FORCEADD TAP..6
(-6525 4325);
FORCEPROP 3 LASTPIN (-6475 4325) SIG_NAME GMI_CPU1_G0_CPU0_G2_TX_DP<15>
J 0
(-6465 4335);
DISPLAY 0.659574 (-6465 4335);
PAINT MONO (-6465 4335);
DISPLAY INVISIBLE (-6465 4335);
FORCEPROP 1 LASTPIN (-6475 4325) BN 15
J 0
(-6527 4333);
DISPLAY 0.489362 (-6527 4333);
PAINT MONO (-6527 4333);
FORCEPROP 2 LAST CDS_LIB standard
J 0
(-6525 4325);
DISPLAY INVISIBLE (-6525 4325);
FORCEPROP 1 LAST BODY_TYPE PLUMBING
J 0
(-6525 4275);
DISPLAY 0.574468 (-6525 4275);
PAINT GREEN (-6525 4275);
DISPLAY INVISIBLE (-6525 4275);
FORCEPROP 1 LAST HDL_TAP TRUE
J 0
(-6200 4200);
DISPLAY 0.574468 (-6200 4200);
PAINT GREEN (-6200 4200);
DISPLAY INVISIBLE (-6200 4200);
FORCEPROP 1 LAST PATH I281
J 0
(-6527 4325);
DISPLAY 0.872340 (-6527 4325);
PAINT GREEN (-6527 4325);
DISPLAY INVISIBLE (-6527 4325);
FORCEADD TAP..6
(-6675 4275);
FORCEPROP 3 LASTPIN (-6625 4275) SIG_NAME GMI_CPU1_G0_CPU0_G2_TX_DN<15>
J 0
(-6615 4285);
DISPLAY 0.659574 (-6615 4285);
PAINT MONO (-6615 4285);
DISPLAY INVISIBLE (-6615 4285);
FORCEPROP 1 LASTPIN (-6625 4275) BN 15
J 0
(-6677 4283);
DISPLAY 0.489362 (-6677 4283);
PAINT MONO (-6677 4283);
FORCEPROP 2 LAST CDS_LIB standard
J 0
(-6675 4275);
DISPLAY INVISIBLE (-6675 4275);
FORCEPROP 1 LAST BODY_TYPE PLUMBING
J 0
(-6675 4225);
DISPLAY 0.574468 (-6675 4225);
PAINT GREEN (-6675 4225);
DISPLAY INVISIBLE (-6675 4225);
FORCEPROP 1 LAST HDL_TAP TRUE
J 0
(-6350 4150);
DISPLAY 0.574468 (-6350 4150);
PAINT GREEN (-6350 4150);
DISPLAY INVISIBLE (-6350 4150);
FORCEPROP 1 LAST PATH I282
J 0
(-6677 4275);
DISPLAY 0.872340 (-6677 4275);
PAINT GREEN (-6677 4275);
DISPLAY INVISIBLE (-6677 4275);
FORCEADD OFFPAGE..1
(-7725 6000);
FORCEPROP 2 LAST $XR0 49 
J 0
(-7946 6000);
DISPLAY 0.638298 (-7946 6000);
PAINT MONO (-7946 6000);
FORCEPROP 2 LAST CDS_LIB standard
J 0
(-7725 6000);
DISPLAY INVISIBLE (-7725 6000);
FORCEPROP 1 LAST OFFPAGE TRUE
J 0
(-7400 5875);
DISPLAY 0.872340 (-7400 5875);
PAINT GREEN (-7400 5875);
DISPLAY INVISIBLE (-7400 5875);
FORCEPROP 1 LAST COMMENT_BODY TRUE
J 0
(-7600 5900);
DISPLAY 0.872340 (-7600 5900);
PAINT GREEN (-7600 5900);
DISPLAY INVISIBLE (-7600 5900);
FORCEPROP 2 LAST PATH I283
J 0
(-7925 6050);
DISPLAY 1.021277 (-7925 6050);
DISPLAY INVISIBLE (-7925 6050);
FORCEADD OFFPAGE..1
(-7725 6050);
FORCEPROP 2 LAST $XR0 49 
J 0
(-7946 6050);
DISPLAY 0.638298 (-7946 6050);
PAINT MONO (-7946 6050);
FORCEPROP 2 LAST CDS_LIB standard
J 0
(-7725 6050);
DISPLAY INVISIBLE (-7725 6050);
FORCEPROP 1 LAST OFFPAGE TRUE
J 0
(-7400 5925);
DISPLAY 0.872340 (-7400 5925);
PAINT GREEN (-7400 5925);
DISPLAY INVISIBLE (-7400 5925);
FORCEPROP 1 LAST COMMENT_BODY TRUE
J 0
(-7600 5950);
DISPLAY 0.872340 (-7600 5950);
PAINT GREEN (-7600 5950);
DISPLAY INVISIBLE (-7600 5950);
FORCEPROP 2 LAST PATH I284
J 0
(-7925 6100);
DISPLAY 1.021277 (-7925 6100);
DISPLAY INVISIBLE (-7925 6100);
FORCEADD TAP..6
R 2
(-3075 2650);
FORCEPROP 3 LASTPIN (-3125 2650) SIG_NAME P5E_CPU0_G3_TX_DP<3>
J 0
(-3115 2660);
DISPLAY 0.659574 (-3115 2660);
PAINT MONO (-3115 2660);
DISPLAY INVISIBLE (-3115 2660);
FORCEPROP 1 LASTPIN (-3125 2650) BN 3
J 2
(-3073 2658);
DISPLAY 0.489362 (-3073 2658);
PAINT MONO (-3073 2658);
FORCEPROP 2 LAST CDS_LIB standard
J 0
(-3075 2650);
DISPLAY INVISIBLE (-3075 2650);
FORCEPROP 2 LAST BOM_COST IO_SLOT
J 0
(-3575 2750);
DISPLAY 0.829787 (-3575 2750);
DISPLAY INVISIBLE (-3575 2750);
FORCEPROP 1 LAST BODY_TYPE PLUMBING
J 2
(-3075 2600);
DISPLAY 0.702128 (-3075 2600);
PAINT GREEN (-3075 2600);
DISPLAY INVISIBLE (-3075 2600);
FORCEPROP 1 LAST HDL_TAP TRUE
J 2
(-3400 2525);
DISPLAY 0.702128 (-3400 2525);
PAINT GREEN (-3400 2525);
DISPLAY INVISIBLE (-3400 2525);
FORCEPROP 1 LAST PATH I285
J 2
(-3073 2650);
DISPLAY 0.872340 (-3073 2650);
PAINT GREEN (-3073 2650);
DISPLAY INVISIBLE (-3073 2650);
FORCEPROP 2 LAST ROOM RISER1
J 0
(-3575 2700);
DISPLAY 0.829787 (-3575 2700);
PAINT RED (-3575 2700);
DISPLAY INVISIBLE (-3575 2700);
FORCEADD TAP..6
R 2
(-2925 2600);
FORCEPROP 3 LASTPIN (-2975 2600) SIG_NAME P5E_CPU0_G3_TX_DN<3>
J 0
(-2965 2610);
DISPLAY 0.659574 (-2965 2610);
PAINT MONO (-2965 2610);
DISPLAY INVISIBLE (-2965 2610);
FORCEPROP 1 LASTPIN (-2975 2600) BN 3
J 2
(-2923 2608);
DISPLAY 0.489362 (-2923 2608);
PAINT MONO (-2923 2608);
FORCEPROP 2 LAST CDS_LIB standard
J 0
(-2925 2600);
DISPLAY INVISIBLE (-2925 2600);
FORCEPROP 2 LAST BOM_COST IO_SLOT
J 0
(-3425 2700);
DISPLAY 0.829787 (-3425 2700);
DISPLAY INVISIBLE (-3425 2700);
FORCEPROP 1 LAST BODY_TYPE PLUMBING
J 2
(-2925 2550);
DISPLAY 0.702128 (-2925 2550);
PAINT GREEN (-2925 2550);
DISPLAY INVISIBLE (-2925 2550);
FORCEPROP 1 LAST HDL_TAP TRUE
J 2
(-3250 2475);
DISPLAY 0.702128 (-3250 2475);
PAINT GREEN (-3250 2475);
DISPLAY INVISIBLE (-3250 2475);
FORCEPROP 1 LAST PATH I286
J 2
(-2923 2600);
DISPLAY 0.872340 (-2923 2600);
PAINT GREEN (-2923 2600);
DISPLAY INVISIBLE (-2923 2600);
FORCEPROP 2 LAST ROOM RISER1
J 0
(-3425 2650);
DISPLAY 0.829787 (-3425 2650);
PAINT RED (-3425 2650);
DISPLAY INVISIBLE (-3425 2650);
FORCEADD TAP..6
R 2
(-2925 2500);
FORCEPROP 3 LASTPIN (-2975 2500) SIG_NAME P5E_CPU0_G3_TX_DN<4>
J 0
(-2965 2510);
DISPLAY 0.659574 (-2965 2510);
PAINT MONO (-2965 2510);
DISPLAY INVISIBLE (-2965 2510);
FORCEPROP 1 LASTPIN (-2975 2500) BN 4
J 2
(-2923 2508);
DISPLAY 0.489362 (-2923 2508);
PAINT MONO (-2923 2508);
FORCEPROP 2 LAST CDS_LIB standard
J 0
(-2925 2500);
DISPLAY INVISIBLE (-2925 2500);
FORCEPROP 2 LAST BOM_COST IO_SLOT
J 0
(-3425 2600);
DISPLAY 0.829787 (-3425 2600);
DISPLAY INVISIBLE (-3425 2600);
FORCEPROP 1 LAST BODY_TYPE PLUMBING
J 2
(-2925 2450);
DISPLAY 0.702128 (-2925 2450);
PAINT GREEN (-2925 2450);
DISPLAY INVISIBLE (-2925 2450);
FORCEPROP 1 LAST HDL_TAP TRUE
J 2
(-3250 2375);
DISPLAY 0.702128 (-3250 2375);
PAINT GREEN (-3250 2375);
DISPLAY INVISIBLE (-3250 2375);
FORCEPROP 1 LAST PATH I287
J 2
(-2923 2500);
DISPLAY 0.872340 (-2923 2500);
PAINT GREEN (-2923 2500);
DISPLAY INVISIBLE (-2923 2500);
FORCEPROP 2 LAST ROOM RISER1
J 0
(-3425 2550);
DISPLAY 0.829787 (-3425 2550);
PAINT RED (-3425 2550);
DISPLAY INVISIBLE (-3425 2550);
FORCEADD TAP..6
R 2
(-2925 2400);
FORCEPROP 3 LASTPIN (-2975 2400) SIG_NAME P5E_CPU0_G3_TX_DN<5>
J 0
(-2965 2410);
DISPLAY 0.659574 (-2965 2410);
PAINT MONO (-2965 2410);
DISPLAY INVISIBLE (-2965 2410);
FORCEPROP 1 LASTPIN (-2975 2400) BN 5
J 2
(-2923 2408);
DISPLAY 0.489362 (-2923 2408);
PAINT MONO (-2923 2408);
FORCEPROP 2 LAST CDS_LIB standard
J 0
(-2925 2400);
DISPLAY INVISIBLE (-2925 2400);
FORCEPROP 2 LAST BOM_COST IO_SLOT
J 0
(-3425 2500);
DISPLAY 0.829787 (-3425 2500);
DISPLAY INVISIBLE (-3425 2500);
FORCEPROP 1 LAST BODY_TYPE PLUMBING
J 2
(-2925 2350);
DISPLAY 0.702128 (-2925 2350);
PAINT GREEN (-2925 2350);
DISPLAY INVISIBLE (-2925 2350);
FORCEPROP 1 LAST HDL_TAP TRUE
J 2
(-3250 2275);
DISPLAY 0.702128 (-3250 2275);
PAINT GREEN (-3250 2275);
DISPLAY INVISIBLE (-3250 2275);
FORCEPROP 1 LAST PATH I288
J 2
(-2923 2400);
DISPLAY 0.872340 (-2923 2400);
PAINT GREEN (-2923 2400);
DISPLAY INVISIBLE (-2923 2400);
FORCEPROP 2 LAST ROOM RISER1
J 0
(-3425 2450);
DISPLAY 0.829787 (-3425 2450);
PAINT RED (-3425 2450);
DISPLAY INVISIBLE (-3425 2450);
FORCEADD TAP..6
R 2
(-2925 2300);
FORCEPROP 3 LASTPIN (-2975 2300) SIG_NAME P5E_CPU0_G3_TX_DN<6>
J 0
(-2965 2310);
DISPLAY 0.659574 (-2965 2310);
PAINT MONO (-2965 2310);
DISPLAY INVISIBLE (-2965 2310);
FORCEPROP 1 LASTPIN (-2975 2300) BN 6
J 2
(-2923 2308);
DISPLAY 0.489362 (-2923 2308);
PAINT MONO (-2923 2308);
FORCEPROP 2 LAST CDS_LIB standard
J 0
(-2925 2300);
DISPLAY INVISIBLE (-2925 2300);
FORCEPROP 2 LAST BOM_COST IO_SLOT
J 0
(-3425 2400);
DISPLAY 0.829787 (-3425 2400);
DISPLAY INVISIBLE (-3425 2400);
FORCEPROP 1 LAST BODY_TYPE PLUMBING
J 2
(-2925 2250);
DISPLAY 0.702128 (-2925 2250);
PAINT GREEN (-2925 2250);
DISPLAY INVISIBLE (-2925 2250);
FORCEPROP 1 LAST HDL_TAP TRUE
J 2
(-3250 2175);
DISPLAY 0.702128 (-3250 2175);
PAINT GREEN (-3250 2175);
DISPLAY INVISIBLE (-3250 2175);
FORCEPROP 1 LAST PATH I289
J 2
(-2923 2300);
DISPLAY 0.872340 (-2923 2300);
PAINT GREEN (-2923 2300);
DISPLAY INVISIBLE (-2923 2300);
FORCEPROP 2 LAST ROOM RISER1
J 0
(-3425 2350);
DISPLAY 0.829787 (-3425 2350);
PAINT RED (-3425 2350);
DISPLAY INVISIBLE (-3425 2350);
FORCEADD OFFPAGE..2
(-1950 3125);
FORCEPROP 2 LAST CDS_LIB standard
J 0
(-1950 3125);
DISPLAY INVISIBLE (-1950 3125);
FORCEPROP 1 LAST OFFPAGE TRUE
J 0
(-1625 3000);
DISPLAY 0.872340 (-1625 3000);
PAINT GREEN (-1625 3000);
DISPLAY INVISIBLE (-1625 3000);
FORCEPROP 1 LAST COMMENT_BODY TRUE
J 0
(-1995 3030);
DISPLAY 0.872340 (-1995 3030);
PAINT GREEN (-1995 3030);
DISPLAY INVISIBLE (-1995 3030);
FORCEPROP 2 LAST PATH I290
J 0
(-1750 3175);
DISPLAY 1.021277 (-1750 3175);
DISPLAY INVISIBLE (-1750 3175);
FORCEADD OFFPAGE..2
(-1950 3175);
FORCEPROP 2 LAST CDS_LIB standard
J 0
(-1950 3175);
DISPLAY INVISIBLE (-1950 3175);
FORCEPROP 1 LAST OFFPAGE TRUE
J 0
(-1625 3050);
DISPLAY 0.872340 (-1625 3050);
PAINT GREEN (-1625 3050);
DISPLAY INVISIBLE (-1625 3050);
FORCEPROP 1 LAST COMMENT_BODY TRUE
J 0
(-1995 3080);
DISPLAY 0.872340 (-1995 3080);
PAINT GREEN (-1995 3080);
DISPLAY INVISIBLE (-1995 3080);
FORCEPROP 2 LAST PATH I291
J 0
(-1750 3225);
DISPLAY 1.021277 (-1750 3225);
DISPLAY INVISIBLE (-1750 3225);
FORCEADD TAP..6
R 2
(-2925 2900);
FORCEPROP 3 LASTPIN (-2975 2900) SIG_NAME P5E_CPU0_G3_TX_DN<0>
J 0
(-2965 2910);
DISPLAY 0.659574 (-2965 2910);
PAINT MONO (-2965 2910);
DISPLAY INVISIBLE (-2965 2910);
FORCEPROP 1 LASTPIN (-2975 2900) BN 0
J 2
(-2923 2908);
DISPLAY 0.489362 (-2923 2908);
PAINT MONO (-2923 2908);
FORCEPROP 2 LAST BOM_COST IO_SLOT
J 0
(-3425 3000);
DISPLAY 0.829787 (-3425 3000);
DISPLAY INVISIBLE (-3425 3000);
FORCEPROP 2 LAST CDS_LIB mstr_standard
J 0
(-2925 2900);
DISPLAY INVISIBLE (-2925 2900);
FORCEPROP 1 LAST BODY_TYPE PLUMBING
J 2
(-2925 2850);
DISPLAY 0.702128 (-2925 2850);
PAINT GREEN (-2925 2850);
DISPLAY INVISIBLE (-2925 2850);
FORCEPROP 1 LAST HDL_TAP TRUE
J 2
(-3250 2775);
DISPLAY 0.702128 (-3250 2775);
PAINT GREEN (-3250 2775);
DISPLAY INVISIBLE (-3250 2775);
FORCEPROP 1 LAST PATH I292
J 2
(-2923 2900);
DISPLAY 0.872340 (-2923 2900);
PAINT GREEN (-2923 2900);
DISPLAY INVISIBLE (-2923 2900);
FORCEPROP 2 LAST ROOM RISER1
J 0
(-3425 2950);
DISPLAY 0.829787 (-3425 2950);
PAINT RED (-3425 2950);
DISPLAY INVISIBLE (-3425 2950);
FORCEADD TAP..6
R 2
(-3075 2850);
FORCEPROP 3 LASTPIN (-3125 2850) SIG_NAME P5E_CPU0_G3_TX_DP<1>
J 0
(-3115 2860);
DISPLAY 0.659574 (-3115 2860);
PAINT MONO (-3115 2860);
DISPLAY INVISIBLE (-3115 2860);
FORCEPROP 1 LASTPIN (-3125 2850) BN 1
J 2
(-3073 2858);
DISPLAY 0.489362 (-3073 2858);
PAINT MONO (-3073 2858);
FORCEPROP 2 LAST CDS_LIB mstr_standard
J 0
(-3075 2850);
DISPLAY INVISIBLE (-3075 2850);
FORCEPROP 2 LAST BOM_COST IO_SLOT
J 0
(-3575 2950);
DISPLAY 0.829787 (-3575 2950);
DISPLAY INVISIBLE (-3575 2950);
FORCEPROP 1 LAST BODY_TYPE PLUMBING
J 2
(-3075 2800);
DISPLAY 0.702128 (-3075 2800);
PAINT GREEN (-3075 2800);
DISPLAY INVISIBLE (-3075 2800);
FORCEPROP 1 LAST HDL_TAP TRUE
J 2
(-3400 2725);
DISPLAY 0.702128 (-3400 2725);
PAINT GREEN (-3400 2725);
DISPLAY INVISIBLE (-3400 2725);
FORCEPROP 1 LAST PATH I293
J 2
(-3073 2850);
DISPLAY 0.872340 (-3073 2850);
PAINT GREEN (-3073 2850);
DISPLAY INVISIBLE (-3073 2850);
FORCEPROP 2 LAST ROOM RISER1
J 0
(-3575 2900);
DISPLAY 0.829787 (-3575 2900);
PAINT RED (-3575 2900);
DISPLAY INVISIBLE (-3575 2900);
FORCEADD TAP..6
R 2
(-3075 2950);
FORCEPROP 3 LASTPIN (-3125 2950) SIG_NAME P5E_CPU0_G3_TX_DP<0>
J 0
(-3115 2960);
DISPLAY 0.659574 (-3115 2960);
PAINT MONO (-3115 2960);
DISPLAY INVISIBLE (-3115 2960);
FORCEPROP 1 LASTPIN (-3125 2950) BN 0
J 2
(-3073 2958);
DISPLAY 0.489362 (-3073 2958);
PAINT MONO (-3073 2958);
FORCEPROP 2 LAST CDS_LIB mstr_standard
J 0
(-3075 2950);
DISPLAY INVISIBLE (-3075 2950);
FORCEPROP 2 LAST BOM_COST IO_SLOT
J 0
(-3575 3050);
DISPLAY 0.829787 (-3575 3050);
DISPLAY INVISIBLE (-3575 3050);
FORCEPROP 1 LAST BODY_TYPE PLUMBING
J 2
(-3075 2900);
DISPLAY 0.702128 (-3075 2900);
PAINT GREEN (-3075 2900);
DISPLAY INVISIBLE (-3075 2900);
FORCEPROP 1 LAST HDL_TAP TRUE
J 2
(-3400 2825);
DISPLAY 0.702128 (-3400 2825);
PAINT GREEN (-3400 2825);
DISPLAY INVISIBLE (-3400 2825);
FORCEPROP 1 LAST PATH I294
J 2
(-3073 2950);
DISPLAY 0.872340 (-3073 2950);
PAINT GREEN (-3073 2950);
DISPLAY INVISIBLE (-3073 2950);
FORCEPROP 2 LAST ROOM RISER1
J 0
(-3575 3000);
DISPLAY 0.829787 (-3575 3000);
PAINT RED (-3575 3000);
DISPLAY INVISIBLE (-3575 3000);
FORCEADD TAP..6
R 2
(-2925 2700);
FORCEPROP 3 LASTPIN (-2975 2700) SIG_NAME P5E_CPU0_G3_TX_DN<2>
J 0
(-2965 2710);
DISPLAY 0.659574 (-2965 2710);
PAINT MONO (-2965 2710);
DISPLAY INVISIBLE (-2965 2710);
FORCEPROP 1 LASTPIN (-2975 2700) BN 2
J 2
(-2923 2708);
DISPLAY 0.489362 (-2923 2708);
PAINT MONO (-2923 2708);
FORCEPROP 2 LAST CDS_LIB standard
J 0
(-2925 2700);
DISPLAY INVISIBLE (-2925 2700);
FORCEPROP 2 LAST BOM_COST IO_SLOT
J 0
(-3425 2800);
DISPLAY 0.829787 (-3425 2800);
DISPLAY INVISIBLE (-3425 2800);
FORCEPROP 1 LAST BODY_TYPE PLUMBING
J 2
(-2925 2650);
DISPLAY 0.702128 (-2925 2650);
PAINT GREEN (-2925 2650);
DISPLAY INVISIBLE (-2925 2650);
FORCEPROP 1 LAST HDL_TAP TRUE
J 2
(-3250 2575);
DISPLAY 0.702128 (-3250 2575);
PAINT GREEN (-3250 2575);
DISPLAY INVISIBLE (-3250 2575);
FORCEPROP 1 LAST PATH I295
J 2
(-2923 2700);
DISPLAY 0.872340 (-2923 2700);
PAINT GREEN (-2923 2700);
DISPLAY INVISIBLE (-2923 2700);
FORCEPROP 2 LAST ROOM RISER1
J 0
(-3425 2750);
DISPLAY 0.829787 (-3425 2750);
PAINT RED (-3425 2750);
DISPLAY INVISIBLE (-3425 2750);
FORCEADD TAP..6
R 2
(-2925 2800);
FORCEPROP 3 LASTPIN (-2975 2800) SIG_NAME P5E_CPU0_G3_TX_DN<1>
J 0
(-2965 2810);
DISPLAY 0.659574 (-2965 2810);
PAINT MONO (-2965 2810);
DISPLAY INVISIBLE (-2965 2810);
FORCEPROP 1 LASTPIN (-2975 2800) BN 1
J 2
(-2923 2808);
DISPLAY 0.489362 (-2923 2808);
PAINT MONO (-2923 2808);
FORCEPROP 2 LAST CDS_LIB mstr_standard
J 0
(-2925 2800);
DISPLAY INVISIBLE (-2925 2800);
FORCEPROP 2 LAST BOM_COST IO_SLOT
J 0
(-3425 2900);
DISPLAY 0.829787 (-3425 2900);
DISPLAY INVISIBLE (-3425 2900);
FORCEPROP 1 LAST BODY_TYPE PLUMBING
J 2
(-2925 2750);
DISPLAY 0.702128 (-2925 2750);
PAINT GREEN (-2925 2750);
DISPLAY INVISIBLE (-2925 2750);
FORCEPROP 1 LAST HDL_TAP TRUE
J 2
(-3250 2675);
DISPLAY 0.702128 (-3250 2675);
PAINT GREEN (-3250 2675);
DISPLAY INVISIBLE (-3250 2675);
FORCEPROP 1 LAST PATH I296
J 2
(-2923 2800);
DISPLAY 0.872340 (-2923 2800);
PAINT GREEN (-2923 2800);
DISPLAY INVISIBLE (-2923 2800);
FORCEPROP 2 LAST ROOM RISER1
J 0
(-3425 2850);
DISPLAY 0.829787 (-3425 2850);
PAINT RED (-3425 2850);
DISPLAY INVISIBLE (-3425 2850);
FORCEADD TAP..6
R 2
(-3075 2750);
FORCEPROP 3 LASTPIN (-3125 2750) SIG_NAME P5E_CPU0_G3_TX_DP<2>
J 0
(-3115 2760);
DISPLAY 0.659574 (-3115 2760);
PAINT MONO (-3115 2760);
DISPLAY INVISIBLE (-3115 2760);
FORCEPROP 1 LASTPIN (-3125 2750) BN 2
J 2
(-3073 2758);
DISPLAY 0.489362 (-3073 2758);
PAINT MONO (-3073 2758);
FORCEPROP 2 LAST CDS_LIB standard
J 0
(-3075 2750);
DISPLAY INVISIBLE (-3075 2750);
FORCEPROP 2 LAST BOM_COST IO_SLOT
J 0
(-3575 2850);
DISPLAY 0.829787 (-3575 2850);
DISPLAY INVISIBLE (-3575 2850);
FORCEPROP 1 LAST BODY_TYPE PLUMBING
J 2
(-3075 2700);
DISPLAY 0.702128 (-3075 2700);
PAINT GREEN (-3075 2700);
DISPLAY INVISIBLE (-3075 2700);
FORCEPROP 1 LAST HDL_TAP TRUE
J 2
(-3400 2625);
DISPLAY 0.702128 (-3400 2625);
PAINT GREEN (-3400 2625);
DISPLAY INVISIBLE (-3400 2625);
FORCEPROP 1 LAST PATH I297
J 2
(-3073 2750);
DISPLAY 0.872340 (-3073 2750);
PAINT GREEN (-3073 2750);
DISPLAY INVISIBLE (-3073 2750);
FORCEPROP 2 LAST ROOM RISER1
J 0
(-3575 2800);
DISPLAY 0.829787 (-3575 2800);
PAINT RED (-3575 2800);
DISPLAY INVISIBLE (-3575 2800);
FORCEADD TAP..6
R 2
(-3075 2350);
FORCEPROP 3 LASTPIN (-3125 2350) SIG_NAME P5E_CPU0_G3_TX_DP<6>
J 0
(-3115 2360);
DISPLAY 0.659574 (-3115 2360);
PAINT MONO (-3115 2360);
DISPLAY INVISIBLE (-3115 2360);
FORCEPROP 1 LASTPIN (-3125 2350) BN 6
J 2
(-3073 2358);
DISPLAY 0.489362 (-3073 2358);
PAINT MONO (-3073 2358);
FORCEPROP 2 LAST CDS_LIB standard
J 0
(-3075 2350);
DISPLAY INVISIBLE (-3075 2350);
FORCEPROP 2 LAST BOM_COST IO_SLOT
J 0
(-3575 2450);
DISPLAY 0.829787 (-3575 2450);
DISPLAY INVISIBLE (-3575 2450);
FORCEPROP 1 LAST BODY_TYPE PLUMBING
J 2
(-3075 2300);
DISPLAY 0.702128 (-3075 2300);
PAINT GREEN (-3075 2300);
DISPLAY INVISIBLE (-3075 2300);
FORCEPROP 1 LAST HDL_TAP TRUE
J 2
(-3400 2225);
DISPLAY 0.702128 (-3400 2225);
PAINT GREEN (-3400 2225);
DISPLAY INVISIBLE (-3400 2225);
FORCEPROP 1 LAST PATH I298
J 2
(-3073 2350);
DISPLAY 0.872340 (-3073 2350);
PAINT GREEN (-3073 2350);
DISPLAY INVISIBLE (-3073 2350);
FORCEPROP 2 LAST ROOM RISER1
J 0
(-3575 2400);
DISPLAY 0.829787 (-3575 2400);
PAINT RED (-3575 2400);
DISPLAY INVISIBLE (-3575 2400);
FORCEADD TAP..6
R 2
(-3075 2550);
FORCEPROP 3 LASTPIN (-3125 2550) SIG_NAME P5E_CPU0_G3_TX_DP<4>
J 0
(-3115 2560);
DISPLAY 0.659574 (-3115 2560);
PAINT MONO (-3115 2560);
DISPLAY INVISIBLE (-3115 2560);
FORCEPROP 1 LASTPIN (-3125 2550) BN 4
J 2
(-3073 2558);
DISPLAY 0.489362 (-3073 2558);
PAINT MONO (-3073 2558);
FORCEPROP 2 LAST CDS_LIB standard
J 0
(-3075 2550);
DISPLAY INVISIBLE (-3075 2550);
FORCEPROP 2 LAST BOM_COST IO_SLOT
J 0
(-3575 2650);
DISPLAY 0.829787 (-3575 2650);
DISPLAY INVISIBLE (-3575 2650);
FORCEPROP 1 LAST BODY_TYPE PLUMBING
J 2
(-3075 2500);
DISPLAY 0.702128 (-3075 2500);
PAINT GREEN (-3075 2500);
DISPLAY INVISIBLE (-3075 2500);
FORCEPROP 1 LAST HDL_TAP TRUE
J 2
(-3400 2425);
DISPLAY 0.702128 (-3400 2425);
PAINT GREEN (-3400 2425);
DISPLAY INVISIBLE (-3400 2425);
FORCEPROP 1 LAST PATH I299
J 2
(-3073 2550);
DISPLAY 0.872340 (-3073 2550);
PAINT GREEN (-3073 2550);
DISPLAY INVISIBLE (-3073 2550);
FORCEPROP 2 LAST ROOM RISER1
J 0
(-3575 2600);
DISPLAY 0.829787 (-3575 2600);
PAINT RED (-3575 2600);
DISPLAY INVISIBLE (-3575 2600);
FORCEADD TAP..6
R 2
(-3075 2450);
FORCEPROP 3 LASTPIN (-3125 2450) SIG_NAME P5E_CPU0_G3_TX_DP<5>
J 0
(-3115 2460);
DISPLAY 0.659574 (-3115 2460);
PAINT MONO (-3115 2460);
DISPLAY INVISIBLE (-3115 2460);
FORCEPROP 1 LASTPIN (-3125 2450) BN 5
J 2
(-3073 2458);
DISPLAY 0.489362 (-3073 2458);
PAINT MONO (-3073 2458);
FORCEPROP 2 LAST CDS_LIB standard
J 0
(-3075 2450);
DISPLAY INVISIBLE (-3075 2450);
FORCEPROP 2 LAST BOM_COST IO_SLOT
J 0
(-3575 2550);
DISPLAY 0.829787 (-3575 2550);
DISPLAY INVISIBLE (-3575 2550);
FORCEPROP 1 LAST BODY_TYPE PLUMBING
J 2
(-3075 2400);
DISPLAY 0.702128 (-3075 2400);
PAINT GREEN (-3075 2400);
DISPLAY INVISIBLE (-3075 2400);
FORCEPROP 1 LAST HDL_TAP TRUE
J 2
(-3400 2325);
DISPLAY 0.702128 (-3400 2325);
PAINT GREEN (-3400 2325);
DISPLAY INVISIBLE (-3400 2325);
FORCEPROP 1 LAST PATH I300
J 2
(-3073 2450);
DISPLAY 0.872340 (-3073 2450);
PAINT GREEN (-3073 2450);
DISPLAY INVISIBLE (-3073 2450);
FORCEPROP 2 LAST ROOM RISER1
J 0
(-3575 2500);
DISPLAY 0.829787 (-3575 2500);
PAINT RED (-3575 2500);
DISPLAY INVISIBLE (-3575 2500);
FORCEADD TAP..6
R 2
(-2925 2200);
FORCEPROP 3 LASTPIN (-2975 2200) SIG_NAME P5E_CPU0_G3_TX_DN<7>
J 0
(-2965 2210);
DISPLAY 0.659574 (-2965 2210);
PAINT MONO (-2965 2210);
DISPLAY INVISIBLE (-2965 2210);
FORCEPROP 1 LASTPIN (-2975 2200) BN 7
J 2
(-2923 2208);
DISPLAY 0.489362 (-2923 2208);
PAINT MONO (-2923 2208);
FORCEPROP 2 LAST CDS_LIB standard
J 0
(-2925 2200);
DISPLAY INVISIBLE (-2925 2200);
FORCEPROP 2 LAST BOM_COST IO_SLOT
J 0
(-3425 2300);
DISPLAY 0.829787 (-3425 2300);
DISPLAY INVISIBLE (-3425 2300);
FORCEPROP 1 LAST BODY_TYPE PLUMBING
J 2
(-2925 2150);
DISPLAY 0.702128 (-2925 2150);
PAINT GREEN (-2925 2150);
DISPLAY INVISIBLE (-2925 2150);
FORCEPROP 1 LAST HDL_TAP TRUE
J 2
(-3250 2075);
DISPLAY 0.702128 (-3250 2075);
PAINT GREEN (-3250 2075);
DISPLAY INVISIBLE (-3250 2075);
FORCEPROP 1 LAST PATH I301
J 2
(-2923 2200);
DISPLAY 0.872340 (-2923 2200);
PAINT GREEN (-2923 2200);
DISPLAY INVISIBLE (-2923 2200);
FORCEPROP 2 LAST ROOM RISER1
J 0
(-3425 2250);
DISPLAY 0.829787 (-3425 2250);
PAINT RED (-3425 2250);
DISPLAY INVISIBLE (-3425 2250);
FORCEADD TAP..6
R 2
(-2925 2100);
FORCEPROP 3 LASTPIN (-2975 2100) SIG_NAME P5E_CPU0_G3_TX_DN<8>
J 0
(-2965 2110);
DISPLAY 0.659574 (-2965 2110);
PAINT MONO (-2965 2110);
DISPLAY INVISIBLE (-2965 2110);
FORCEPROP 1 LASTPIN (-2975 2100) BN 8
J 2
(-2923 2108);
DISPLAY 0.489362 (-2923 2108);
PAINT MONO (-2923 2108);
FORCEPROP 2 LAST CDS_LIB standard
J 0
(-2925 2100);
DISPLAY INVISIBLE (-2925 2100);
FORCEPROP 2 LAST BOM_COST IO_SLOT
J 0
(-3425 2200);
DISPLAY 0.829787 (-3425 2200);
DISPLAY INVISIBLE (-3425 2200);
FORCEPROP 1 LAST BODY_TYPE PLUMBING
J 2
(-2925 2050);
DISPLAY 0.702128 (-2925 2050);
PAINT GREEN (-2925 2050);
DISPLAY INVISIBLE (-2925 2050);
FORCEPROP 1 LAST HDL_TAP TRUE
J 2
(-3250 1975);
DISPLAY 0.702128 (-3250 1975);
PAINT GREEN (-3250 1975);
DISPLAY INVISIBLE (-3250 1975);
FORCEPROP 1 LAST PATH I302
J 2
(-2923 2100);
DISPLAY 0.872340 (-2923 2100);
PAINT GREEN (-2923 2100);
DISPLAY INVISIBLE (-2923 2100);
FORCEPROP 2 LAST ROOM RISER1
J 0
(-3425 2150);
DISPLAY 0.829787 (-3425 2150);
PAINT RED (-3425 2150);
DISPLAY INVISIBLE (-3425 2150);
FORCEADD TAP..6
R 2
(-3075 2250);
FORCEPROP 3 LASTPIN (-3125 2250) SIG_NAME P5E_CPU0_G3_TX_DP<7>
J 0
(-3115 2260);
DISPLAY 0.659574 (-3115 2260);
PAINT MONO (-3115 2260);
DISPLAY INVISIBLE (-3115 2260);
FORCEPROP 1 LASTPIN (-3125 2250) BN 7
J 2
(-3073 2258);
DISPLAY 0.489362 (-3073 2258);
PAINT MONO (-3073 2258);
FORCEPROP 2 LAST CDS_LIB standard
J 0
(-3075 2250);
DISPLAY INVISIBLE (-3075 2250);
FORCEPROP 2 LAST BOM_COST IO_SLOT
J 0
(-3575 2350);
DISPLAY 0.829787 (-3575 2350);
DISPLAY INVISIBLE (-3575 2350);
FORCEPROP 1 LAST BODY_TYPE PLUMBING
J 2
(-3075 2200);
DISPLAY 0.702128 (-3075 2200);
PAINT GREEN (-3075 2200);
DISPLAY INVISIBLE (-3075 2200);
FORCEPROP 1 LAST HDL_TAP TRUE
J 2
(-3400 2125);
DISPLAY 0.702128 (-3400 2125);
PAINT GREEN (-3400 2125);
DISPLAY INVISIBLE (-3400 2125);
FORCEPROP 1 LAST PATH I303
J 2
(-3073 2250);
DISPLAY 0.872340 (-3073 2250);
PAINT GREEN (-3073 2250);
DISPLAY INVISIBLE (-3073 2250);
FORCEPROP 2 LAST ROOM RISER1
J 0
(-3575 2300);
DISPLAY 0.829787 (-3575 2300);
PAINT RED (-3575 2300);
DISPLAY INVISIBLE (-3575 2300);
FORCEADD TAP..6
R 2
(-3075 2150);
FORCEPROP 3 LASTPIN (-3125 2150) SIG_NAME P5E_CPU0_G3_TX_DP<8>
J 0
(-3115 2160);
DISPLAY 0.659574 (-3115 2160);
PAINT MONO (-3115 2160);
DISPLAY INVISIBLE (-3115 2160);
FORCEPROP 1 LASTPIN (-3125 2150) BN 8
J 2
(-3073 2158);
DISPLAY 0.489362 (-3073 2158);
PAINT MONO (-3073 2158);
FORCEPROP 2 LAST CDS_LIB standard
J 0
(-3075 2150);
DISPLAY INVISIBLE (-3075 2150);
FORCEPROP 2 LAST BOM_COST IO_SLOT
J 0
(-3575 2250);
DISPLAY 0.829787 (-3575 2250);
DISPLAY INVISIBLE (-3575 2250);
FORCEPROP 1 LAST BODY_TYPE PLUMBING
J 2
(-3075 2100);
DISPLAY 0.702128 (-3075 2100);
PAINT GREEN (-3075 2100);
DISPLAY INVISIBLE (-3075 2100);
FORCEPROP 1 LAST HDL_TAP TRUE
J 2
(-3400 2025);
DISPLAY 0.702128 (-3400 2025);
PAINT GREEN (-3400 2025);
DISPLAY INVISIBLE (-3400 2025);
FORCEPROP 1 LAST PATH I304
J 2
(-3073 2150);
DISPLAY 0.872340 (-3073 2150);
PAINT GREEN (-3073 2150);
DISPLAY INVISIBLE (-3073 2150);
FORCEPROP 2 LAST ROOM RISER1
J 0
(-3575 2200);
DISPLAY 0.829787 (-3575 2200);
PAINT RED (-3575 2200);
DISPLAY INVISIBLE (-3575 2200);
FORCEADD TAP..6
R 2
(-3075 2050);
FORCEPROP 3 LASTPIN (-3125 2050) SIG_NAME P5E_CPU0_G3_TX_DP<9>
J 0
(-3115 2060);
DISPLAY 0.659574 (-3115 2060);
PAINT MONO (-3115 2060);
DISPLAY INVISIBLE (-3115 2060);
FORCEPROP 1 LASTPIN (-3125 2050) BN 9
J 2
(-3073 2058);
DISPLAY 0.489362 (-3073 2058);
PAINT MONO (-3073 2058);
FORCEPROP 2 LAST CDS_LIB standard
J 0
(-3075 2050);
DISPLAY INVISIBLE (-3075 2050);
FORCEPROP 2 LAST BOM_COST IO_SLOT
J 0
(-3575 2150);
DISPLAY 0.829787 (-3575 2150);
DISPLAY INVISIBLE (-3575 2150);
FORCEPROP 1 LAST BODY_TYPE PLUMBING
J 2
(-3075 2000);
DISPLAY 0.702128 (-3075 2000);
PAINT GREEN (-3075 2000);
DISPLAY INVISIBLE (-3075 2000);
FORCEPROP 1 LAST HDL_TAP TRUE
J 2
(-3400 1925);
DISPLAY 0.702128 (-3400 1925);
PAINT GREEN (-3400 1925);
DISPLAY INVISIBLE (-3400 1925);
FORCEPROP 1 LAST PATH I305
J 2
(-3073 2050);
DISPLAY 0.872340 (-3073 2050);
PAINT GREEN (-3073 2050);
DISPLAY INVISIBLE (-3073 2050);
FORCEPROP 2 LAST ROOM RISER1
J 0
(-3575 2100);
DISPLAY 0.829787 (-3575 2100);
PAINT RED (-3575 2100);
DISPLAY INVISIBLE (-3575 2100);
FORCEADD TAP..6
R 2
(-2925 2000);
FORCEPROP 3 LASTPIN (-2975 2000) SIG_NAME P5E_CPU0_G3_TX_DN<9>
J 0
(-2965 2010);
DISPLAY 0.659574 (-2965 2010);
PAINT MONO (-2965 2010);
DISPLAY INVISIBLE (-2965 2010);
FORCEPROP 1 LASTPIN (-2975 2000) BN 9
J 2
(-2923 2008);
DISPLAY 0.489362 (-2923 2008);
PAINT MONO (-2923 2008);
FORCEPROP 2 LAST CDS_LIB standard
J 0
(-2925 2000);
DISPLAY INVISIBLE (-2925 2000);
FORCEPROP 2 LAST BOM_COST IO_SLOT
J 0
(-3425 2100);
DISPLAY 0.829787 (-3425 2100);
DISPLAY INVISIBLE (-3425 2100);
FORCEPROP 1 LAST BODY_TYPE PLUMBING
J 2
(-2925 1950);
DISPLAY 0.702128 (-2925 1950);
PAINT GREEN (-2925 1950);
DISPLAY INVISIBLE (-2925 1950);
FORCEPROP 1 LAST HDL_TAP TRUE
J 2
(-3250 1875);
DISPLAY 0.702128 (-3250 1875);
PAINT GREEN (-3250 1875);
DISPLAY INVISIBLE (-3250 1875);
FORCEPROP 1 LAST PATH I306
J 2
(-2923 2000);
DISPLAY 0.872340 (-2923 2000);
PAINT GREEN (-2923 2000);
DISPLAY INVISIBLE (-2923 2000);
FORCEPROP 2 LAST ROOM RISER1
J 0
(-3425 2050);
DISPLAY 0.829787 (-3425 2050);
PAINT RED (-3425 2050);
DISPLAY INVISIBLE (-3425 2050);
FORCEADD TAP..6
R 2
(-2925 1800);
FORCEPROP 3 LASTPIN (-2975 1800) SIG_NAME P5E_CPU0_G3_TX_DN<11>
J 0
(-2965 1810);
DISPLAY 0.659574 (-2965 1810);
PAINT MONO (-2965 1810);
DISPLAY INVISIBLE (-2965 1810);
FORCEPROP 1 LASTPIN (-2975 1800) BN 11
J 2
(-2923 1808);
DISPLAY 0.489362 (-2923 1808);
PAINT MONO (-2923 1808);
FORCEPROP 2 LAST CDS_LIB standard
J 0
(-2925 1800);
DISPLAY INVISIBLE (-2925 1800);
FORCEPROP 2 LAST BOM_COST IO_SLOT
J 0
(-3425 1900);
DISPLAY 0.829787 (-3425 1900);
DISPLAY INVISIBLE (-3425 1900);
FORCEPROP 1 LAST BODY_TYPE PLUMBING
J 2
(-2925 1750);
DISPLAY 0.702128 (-2925 1750);
PAINT GREEN (-2925 1750);
DISPLAY INVISIBLE (-2925 1750);
FORCEPROP 1 LAST HDL_TAP TRUE
J 2
(-3250 1675);
DISPLAY 0.702128 (-3250 1675);
PAINT GREEN (-3250 1675);
DISPLAY INVISIBLE (-3250 1675);
FORCEPROP 1 LAST PATH I307
J 2
(-2923 1800);
DISPLAY 0.872340 (-2923 1800);
PAINT GREEN (-2923 1800);
DISPLAY INVISIBLE (-2923 1800);
FORCEPROP 2 LAST ROOM RISER1
J 0
(-3425 1850);
DISPLAY 0.829787 (-3425 1850);
PAINT RED (-3425 1850);
DISPLAY INVISIBLE (-3425 1850);
FORCEADD TAP..6
R 2
(-2925 1900);
FORCEPROP 3 LASTPIN (-2975 1900) SIG_NAME P5E_CPU0_G3_TX_DN<10>
J 0
(-2965 1910);
DISPLAY 0.659574 (-2965 1910);
PAINT MONO (-2965 1910);
DISPLAY INVISIBLE (-2965 1910);
FORCEPROP 1 LASTPIN (-2975 1900) BN 10
J 2
(-2923 1908);
DISPLAY 0.489362 (-2923 1908);
PAINT MONO (-2923 1908);
FORCEPROP 2 LAST CDS_LIB standard
J 0
(-2925 1900);
DISPLAY INVISIBLE (-2925 1900);
FORCEPROP 2 LAST BOM_COST IO_SLOT
J 0
(-3425 2000);
DISPLAY 0.829787 (-3425 2000);
DISPLAY INVISIBLE (-3425 2000);
FORCEPROP 1 LAST BODY_TYPE PLUMBING
J 2
(-2925 1850);
DISPLAY 0.702128 (-2925 1850);
PAINT GREEN (-2925 1850);
DISPLAY INVISIBLE (-2925 1850);
FORCEPROP 1 LAST HDL_TAP TRUE
J 2
(-3250 1775);
DISPLAY 0.702128 (-3250 1775);
PAINT GREEN (-3250 1775);
DISPLAY INVISIBLE (-3250 1775);
FORCEPROP 1 LAST PATH I308
J 2
(-2923 1900);
DISPLAY 0.872340 (-2923 1900);
PAINT GREEN (-2923 1900);
DISPLAY INVISIBLE (-2923 1900);
FORCEPROP 2 LAST ROOM RISER1
J 0
(-3425 1950);
DISPLAY 0.829787 (-3425 1950);
PAINT RED (-3425 1950);
DISPLAY INVISIBLE (-3425 1950);
FORCEADD TAP..6
R 2
(-3075 1950);
FORCEPROP 3 LASTPIN (-3125 1950) SIG_NAME P5E_CPU0_G3_TX_DP<10>
J 0
(-3115 1960);
DISPLAY 0.659574 (-3115 1960);
PAINT MONO (-3115 1960);
DISPLAY INVISIBLE (-3115 1960);
FORCEPROP 1 LASTPIN (-3125 1950) BN 10
J 2
(-3073 1958);
DISPLAY 0.489362 (-3073 1958);
PAINT MONO (-3073 1958);
FORCEPROP 2 LAST CDS_LIB standard
J 0
(-3075 1950);
DISPLAY INVISIBLE (-3075 1950);
FORCEPROP 2 LAST BOM_COST IO_SLOT
J 0
(-3575 2050);
DISPLAY 0.829787 (-3575 2050);
DISPLAY INVISIBLE (-3575 2050);
FORCEPROP 1 LAST BODY_TYPE PLUMBING
J 2
(-3075 1900);
DISPLAY 0.702128 (-3075 1900);
PAINT GREEN (-3075 1900);
DISPLAY INVISIBLE (-3075 1900);
FORCEPROP 1 LAST HDL_TAP TRUE
J 2
(-3400 1825);
DISPLAY 0.702128 (-3400 1825);
PAINT GREEN (-3400 1825);
DISPLAY INVISIBLE (-3400 1825);
FORCEPROP 1 LAST PATH I309
J 2
(-3073 1950);
DISPLAY 0.872340 (-3073 1950);
PAINT GREEN (-3073 1950);
DISPLAY INVISIBLE (-3073 1950);
FORCEPROP 2 LAST ROOM RISER1
J 0
(-3575 2000);
DISPLAY 0.829787 (-3575 2000);
PAINT RED (-3575 2000);
DISPLAY INVISIBLE (-3575 2000);
FORCEADD TAP..6
R 2
(-3075 1850);
FORCEPROP 3 LASTPIN (-3125 1850) SIG_NAME P5E_CPU0_G3_TX_DP<11>
J 0
(-3115 1860);
DISPLAY 0.659574 (-3115 1860);
PAINT MONO (-3115 1860);
DISPLAY INVISIBLE (-3115 1860);
FORCEPROP 1 LASTPIN (-3125 1850) BN 11
J 2
(-3073 1858);
DISPLAY 0.489362 (-3073 1858);
PAINT MONO (-3073 1858);
FORCEPROP 2 LAST CDS_LIB standard
J 0
(-3075 1850);
DISPLAY INVISIBLE (-3075 1850);
FORCEPROP 2 LAST BOM_COST IO_SLOT
J 0
(-3575 1950);
DISPLAY 0.829787 (-3575 1950);
DISPLAY INVISIBLE (-3575 1950);
FORCEPROP 1 LAST BODY_TYPE PLUMBING
J 2
(-3075 1800);
DISPLAY 0.702128 (-3075 1800);
PAINT GREEN (-3075 1800);
DISPLAY INVISIBLE (-3075 1800);
FORCEPROP 1 LAST HDL_TAP TRUE
J 2
(-3400 1725);
DISPLAY 0.702128 (-3400 1725);
PAINT GREEN (-3400 1725);
DISPLAY INVISIBLE (-3400 1725);
FORCEPROP 1 LAST PATH I310
J 2
(-3073 1850);
DISPLAY 0.872340 (-3073 1850);
PAINT GREEN (-3073 1850);
DISPLAY INVISIBLE (-3073 1850);
FORCEPROP 2 LAST ROOM RISER1
J 0
(-3575 1900);
DISPLAY 0.829787 (-3575 1900);
PAINT RED (-3575 1900);
DISPLAY INVISIBLE (-3575 1900);
FORCEADD TAP..6
R 2
(-2925 1700);
FORCEPROP 3 LASTPIN (-2975 1700) SIG_NAME P5E_CPU0_G3_TX_DN<12>
J 0
(-2965 1710);
DISPLAY 0.659574 (-2965 1710);
PAINT MONO (-2965 1710);
DISPLAY INVISIBLE (-2965 1710);
FORCEPROP 1 LASTPIN (-2975 1700) BN 12
J 2
(-2923 1708);
DISPLAY 0.489362 (-2923 1708);
PAINT MONO (-2923 1708);
FORCEPROP 2 LAST CDS_LIB standard
J 0
(-2925 1700);
DISPLAY INVISIBLE (-2925 1700);
FORCEPROP 2 LAST BOM_COST IO_SLOT
J 0
(-3425 1800);
DISPLAY 0.829787 (-3425 1800);
DISPLAY INVISIBLE (-3425 1800);
FORCEPROP 1 LAST BODY_TYPE PLUMBING
J 2
(-2925 1650);
DISPLAY 0.702128 (-2925 1650);
PAINT GREEN (-2925 1650);
DISPLAY INVISIBLE (-2925 1650);
FORCEPROP 1 LAST HDL_TAP TRUE
J 2
(-3250 1575);
DISPLAY 0.702128 (-3250 1575);
PAINT GREEN (-3250 1575);
DISPLAY INVISIBLE (-3250 1575);
FORCEPROP 1 LAST PATH I311
J 2
(-2923 1700);
DISPLAY 0.872340 (-2923 1700);
PAINT GREEN (-2923 1700);
DISPLAY INVISIBLE (-2923 1700);
FORCEPROP 2 LAST ROOM RISER1
J 0
(-3425 1750);
DISPLAY 0.829787 (-3425 1750);
PAINT RED (-3425 1750);
DISPLAY INVISIBLE (-3425 1750);
FORCEADD TAP..6
R 2
(-2925 1600);
FORCEPROP 3 LASTPIN (-2975 1600) SIG_NAME P5E_CPU0_G3_TX_DN<13>
J 0
(-2965 1610);
DISPLAY 0.659574 (-2965 1610);
PAINT MONO (-2965 1610);
DISPLAY INVISIBLE (-2965 1610);
FORCEPROP 1 LASTPIN (-2975 1600) BN 13
J 2
(-2923 1608);
DISPLAY 0.489362 (-2923 1608);
PAINT MONO (-2923 1608);
FORCEPROP 2 LAST CDS_LIB standard
J 0
(-2925 1600);
DISPLAY INVISIBLE (-2925 1600);
FORCEPROP 2 LAST BOM_COST IO_SLOT
J 0
(-3425 1700);
DISPLAY 0.829787 (-3425 1700);
DISPLAY INVISIBLE (-3425 1700);
FORCEPROP 1 LAST BODY_TYPE PLUMBING
J 2
(-2925 1550);
DISPLAY 0.702128 (-2925 1550);
PAINT GREEN (-2925 1550);
DISPLAY INVISIBLE (-2925 1550);
FORCEPROP 1 LAST HDL_TAP TRUE
J 2
(-3250 1475);
DISPLAY 0.702128 (-3250 1475);
PAINT GREEN (-3250 1475);
DISPLAY INVISIBLE (-3250 1475);
FORCEPROP 1 LAST PATH I312
J 2
(-2923 1600);
DISPLAY 0.872340 (-2923 1600);
PAINT GREEN (-2923 1600);
DISPLAY INVISIBLE (-2923 1600);
FORCEPROP 2 LAST ROOM RISER1
J 0
(-3425 1650);
DISPLAY 0.829787 (-3425 1650);
PAINT RED (-3425 1650);
DISPLAY INVISIBLE (-3425 1650);
FORCEADD TAP..6
R 2
(-3075 1650);
FORCEPROP 3 LASTPIN (-3125 1650) SIG_NAME P5E_CPU0_G3_TX_DP<13>
J 0
(-3115 1660);
DISPLAY 0.659574 (-3115 1660);
PAINT MONO (-3115 1660);
DISPLAY INVISIBLE (-3115 1660);
FORCEPROP 1 LASTPIN (-3125 1650) BN 13
J 2
(-3073 1658);
DISPLAY 0.489362 (-3073 1658);
PAINT MONO (-3073 1658);
FORCEPROP 2 LAST CDS_LIB standard
J 0
(-3075 1650);
DISPLAY INVISIBLE (-3075 1650);
FORCEPROP 2 LAST BOM_COST IO_SLOT
J 0
(-3575 1750);
DISPLAY 0.829787 (-3575 1750);
DISPLAY INVISIBLE (-3575 1750);
FORCEPROP 1 LAST BODY_TYPE PLUMBING
J 2
(-3075 1600);
DISPLAY 0.702128 (-3075 1600);
PAINT GREEN (-3075 1600);
DISPLAY INVISIBLE (-3075 1600);
FORCEPROP 1 LAST HDL_TAP TRUE
J 2
(-3400 1525);
DISPLAY 0.702128 (-3400 1525);
PAINT GREEN (-3400 1525);
DISPLAY INVISIBLE (-3400 1525);
FORCEPROP 1 LAST PATH I313
J 2
(-3073 1650);
DISPLAY 0.872340 (-3073 1650);
PAINT GREEN (-3073 1650);
DISPLAY INVISIBLE (-3073 1650);
FORCEPROP 2 LAST ROOM RISER1
J 0
(-3575 1700);
DISPLAY 0.829787 (-3575 1700);
PAINT RED (-3575 1700);
DISPLAY INVISIBLE (-3575 1700);
FORCEADD TAP..6
R 2
(-3075 1750);
FORCEPROP 3 LASTPIN (-3125 1750) SIG_NAME P5E_CPU0_G3_TX_DP<12>
J 0
(-3115 1760);
DISPLAY 0.659574 (-3115 1760);
PAINT MONO (-3115 1760);
DISPLAY INVISIBLE (-3115 1760);
FORCEPROP 1 LASTPIN (-3125 1750) BN 12
J 2
(-3073 1758);
DISPLAY 0.489362 (-3073 1758);
PAINT MONO (-3073 1758);
FORCEPROP 2 LAST CDS_LIB standard
J 0
(-3075 1750);
DISPLAY INVISIBLE (-3075 1750);
FORCEPROP 2 LAST BOM_COST IO_SLOT
J 0
(-3575 1850);
DISPLAY 0.829787 (-3575 1850);
DISPLAY INVISIBLE (-3575 1850);
FORCEPROP 1 LAST BODY_TYPE PLUMBING
J 2
(-3075 1700);
DISPLAY 0.702128 (-3075 1700);
PAINT GREEN (-3075 1700);
DISPLAY INVISIBLE (-3075 1700);
FORCEPROP 1 LAST HDL_TAP TRUE
J 2
(-3400 1625);
DISPLAY 0.702128 (-3400 1625);
PAINT GREEN (-3400 1625);
DISPLAY INVISIBLE (-3400 1625);
FORCEPROP 1 LAST PATH I314
J 2
(-3073 1750);
DISPLAY 0.872340 (-3073 1750);
PAINT GREEN (-3073 1750);
DISPLAY INVISIBLE (-3073 1750);
FORCEPROP 2 LAST ROOM RISER1
J 0
(-3575 1800);
DISPLAY 0.829787 (-3575 1800);
PAINT RED (-3575 1800);
DISPLAY INVISIBLE (-3575 1800);
FORCEADD TAP..6
R 2
(-3075 1550);
FORCEPROP 3 LASTPIN (-3125 1550) SIG_NAME P5E_CPU0_G3_TX_DP<14>
J 0
(-3115 1560);
DISPLAY 0.659574 (-3115 1560);
PAINT MONO (-3115 1560);
DISPLAY INVISIBLE (-3115 1560);
FORCEPROP 1 LASTPIN (-3125 1550) BN 14
J 2
(-3073 1558);
DISPLAY 0.489362 (-3073 1558);
PAINT MONO (-3073 1558);
FORCEPROP 2 LAST CDS_LIB standard
J 0
(-3075 1550);
DISPLAY INVISIBLE (-3075 1550);
FORCEPROP 2 LAST BOM_COST IO_SLOT
J 0
(-3575 1650);
DISPLAY 0.829787 (-3575 1650);
DISPLAY INVISIBLE (-3575 1650);
FORCEPROP 1 LAST BODY_TYPE PLUMBING
J 2
(-3075 1500);
DISPLAY 0.702128 (-3075 1500);
PAINT GREEN (-3075 1500);
DISPLAY INVISIBLE (-3075 1500);
FORCEPROP 1 LAST HDL_TAP TRUE
J 2
(-3400 1425);
DISPLAY 0.702128 (-3400 1425);
PAINT GREEN (-3400 1425);
DISPLAY INVISIBLE (-3400 1425);
FORCEPROP 1 LAST PATH I315
J 2
(-3073 1550);
DISPLAY 0.872340 (-3073 1550);
PAINT GREEN (-3073 1550);
DISPLAY INVISIBLE (-3073 1550);
FORCEPROP 2 LAST ROOM RISER1
J 0
(-3575 1600);
DISPLAY 0.829787 (-3575 1600);
PAINT RED (-3575 1600);
DISPLAY INVISIBLE (-3575 1600);
FORCEADD TAP..6
R 2
(-2925 1500);
FORCEPROP 3 LASTPIN (-2975 1500) SIG_NAME P5E_CPU0_G3_TX_DN<14>
J 0
(-2965 1510);
DISPLAY 0.659574 (-2965 1510);
PAINT MONO (-2965 1510);
DISPLAY INVISIBLE (-2965 1510);
FORCEPROP 1 LASTPIN (-2975 1500) BN 14
J 2
(-2923 1508);
DISPLAY 0.489362 (-2923 1508);
PAINT MONO (-2923 1508);
FORCEPROP 2 LAST BOM_COST IO_SLOT
J 0
(-3425 1600);
DISPLAY 0.829787 (-3425 1600);
DISPLAY INVISIBLE (-3425 1600);
FORCEPROP 2 LAST CDS_LIB standard
J 0
(-2925 1500);
DISPLAY INVISIBLE (-2925 1500);
FORCEPROP 1 LAST BODY_TYPE PLUMBING
J 2
(-2925 1450);
DISPLAY 0.702128 (-2925 1450);
PAINT GREEN (-2925 1450);
DISPLAY INVISIBLE (-2925 1450);
FORCEPROP 1 LAST HDL_TAP TRUE
J 2
(-3250 1375);
DISPLAY 0.702128 (-3250 1375);
PAINT GREEN (-3250 1375);
DISPLAY INVISIBLE (-3250 1375);
FORCEPROP 1 LAST PATH I316
J 2
(-2923 1500);
DISPLAY 0.872340 (-2923 1500);
PAINT GREEN (-2923 1500);
DISPLAY INVISIBLE (-2923 1500);
FORCEPROP 2 LAST ROOM RISER1
J 0
(-3425 1550);
DISPLAY 0.829787 (-3425 1550);
PAINT RED (-3425 1550);
DISPLAY INVISIBLE (-3425 1550);
FORCEADD TAP..6
R 2
(-2925 1400);
FORCEPROP 3 LASTPIN (-2975 1400) SIG_NAME P5E_CPU0_G3_TX_DN<15>
J 0
(-2965 1410);
DISPLAY 0.659574 (-2965 1410);
PAINT MONO (-2965 1410);
DISPLAY INVISIBLE (-2965 1410);
FORCEPROP 1 LASTPIN (-2975 1400) BN 15
J 2
(-2923 1408);
DISPLAY 0.489362 (-2923 1408);
PAINT MONO (-2923 1408);
FORCEPROP 2 LAST CDS_LIB standard
J 0
(-2925 1400);
DISPLAY INVISIBLE (-2925 1400);
FORCEPROP 2 LAST BOM_COST IO_SLOT
J 0
(-3425 1500);
DISPLAY 0.829787 (-3425 1500);
DISPLAY INVISIBLE (-3425 1500);
FORCEPROP 1 LAST BODY_TYPE PLUMBING
J 2
(-2925 1350);
DISPLAY 0.702128 (-2925 1350);
PAINT GREEN (-2925 1350);
DISPLAY INVISIBLE (-2925 1350);
FORCEPROP 1 LAST HDL_TAP TRUE
J 2
(-3250 1275);
DISPLAY 0.702128 (-3250 1275);
PAINT GREEN (-3250 1275);
DISPLAY INVISIBLE (-3250 1275);
FORCEPROP 1 LAST PATH I317
J 2
(-2923 1400);
DISPLAY 0.872340 (-2923 1400);
PAINT GREEN (-2923 1400);
DISPLAY INVISIBLE (-2923 1400);
FORCEPROP 2 LAST ROOM RISER1
J 0
(-3425 1450);
DISPLAY 0.829787 (-3425 1450);
PAINT RED (-3425 1450);
DISPLAY INVISIBLE (-3425 1450);
FORCEADD TAP..6
R 2
(-3075 1450);
FORCEPROP 3 LASTPIN (-3125 1450) SIG_NAME P5E_CPU0_G3_TX_DP<15>
J 0
(-3115 1460);
DISPLAY 0.659574 (-3115 1460);
PAINT MONO (-3115 1460);
DISPLAY INVISIBLE (-3115 1460);
FORCEPROP 1 LASTPIN (-3125 1450) BN 15
J 2
(-3073 1458);
DISPLAY 0.489362 (-3073 1458);
PAINT MONO (-3073 1458);
FORCEPROP 2 LAST CDS_LIB standard
J 0
(-3075 1450);
DISPLAY INVISIBLE (-3075 1450);
FORCEPROP 2 LAST BOM_COST IO_SLOT
J 0
(-3575 1550);
DISPLAY 0.829787 (-3575 1550);
DISPLAY INVISIBLE (-3575 1550);
FORCEPROP 1 LAST BODY_TYPE PLUMBING
J 2
(-3075 1400);
DISPLAY 0.702128 (-3075 1400);
PAINT GREEN (-3075 1400);
DISPLAY INVISIBLE (-3075 1400);
FORCEPROP 1 LAST HDL_TAP TRUE
J 2
(-3400 1325);
DISPLAY 0.702128 (-3400 1325);
PAINT GREEN (-3400 1325);
DISPLAY INVISIBLE (-3400 1325);
FORCEPROP 1 LAST PATH I318
J 2
(-3073 1450);
DISPLAY 0.872340 (-3073 1450);
PAINT GREEN (-3073 1450);
DISPLAY INVISIBLE (-3073 1450);
FORCEPROP 2 LAST ROOM RISER1
J 0
(-3575 1500);
DISPLAY 0.829787 (-3575 1500);
PAINT RED (-3575 1500);
DISPLAY INVISIBLE (-3575 1500);
FORCEADD TAP..6
(-6500 2950);
FORCEPROP 3 LASTPIN (-6450 2950) SIG_NAME P5E_CPU0_G3_RX_DP<0>
J 0
(-6440 2960);
DISPLAY 0.659574 (-6440 2960);
PAINT MONO (-6440 2960);
DISPLAY INVISIBLE (-6440 2960);
FORCEPROP 1 LASTPIN (-6450 2950) BN 0
J 0
(-6502 2958);
DISPLAY 0.489362 (-6502 2958);
PAINT MONO (-6502 2958);
FORCEPROP 2 LAST CDS_LIB mstr_standard
J 0
(-6500 2950);
DISPLAY INVISIBLE (-6500 2950);
FORCEPROP 1 LAST BODY_TYPE PLUMBING
J 0
(-6500 2900);
DISPLAY 0.574468 (-6500 2900);
PAINT GREEN (-6500 2900);
DISPLAY INVISIBLE (-6500 2900);
FORCEPROP 1 LAST HDL_TAP TRUE
J 0
(-6175 2825);
DISPLAY 0.574468 (-6175 2825);
PAINT GREEN (-6175 2825);
DISPLAY INVISIBLE (-6175 2825);
FORCEPROP 1 LAST PATH I319
J 0
(-6502 2950);
DISPLAY 0.872340 (-6502 2950);
PAINT GREEN (-6502 2950);
DISPLAY INVISIBLE (-6502 2950);
FORCEADD TAP..6
(-6500 2850);
FORCEPROP 3 LASTPIN (-6450 2850) SIG_NAME P5E_CPU0_G3_RX_DP<1>
J 0
(-6440 2860);
DISPLAY 0.659574 (-6440 2860);
PAINT MONO (-6440 2860);
DISPLAY INVISIBLE (-6440 2860);
FORCEPROP 1 LASTPIN (-6450 2850) BN 1
J 0
(-6502 2858);
DISPLAY 0.489362 (-6502 2858);
PAINT MONO (-6502 2858);
FORCEPROP 2 LAST CDS_LIB mstr_standard
J 0
(-6500 2850);
DISPLAY INVISIBLE (-6500 2850);
FORCEPROP 1 LAST BODY_TYPE PLUMBING
J 0
(-6500 2800);
DISPLAY 0.574468 (-6500 2800);
PAINT GREEN (-6500 2800);
DISPLAY INVISIBLE (-6500 2800);
FORCEPROP 1 LAST HDL_TAP TRUE
J 0
(-6175 2725);
DISPLAY 0.574468 (-6175 2725);
PAINT GREEN (-6175 2725);
DISPLAY INVISIBLE (-6175 2725);
FORCEPROP 1 LAST PATH I320
J 0
(-6502 2850);
DISPLAY 0.872340 (-6502 2850);
PAINT GREEN (-6502 2850);
DISPLAY INVISIBLE (-6502 2850);
FORCEADD TAP..6
(-6650 2900);
FORCEPROP 3 LASTPIN (-6600 2900) SIG_NAME P5E_CPU0_G3_RX_DN<0>
J 0
(-6590 2910);
DISPLAY 0.659574 (-6590 2910);
PAINT MONO (-6590 2910);
DISPLAY INVISIBLE (-6590 2910);
FORCEPROP 1 LASTPIN (-6600 2900) BN 0
J 0
(-6652 2908);
DISPLAY 0.489362 (-6652 2908);
PAINT MONO (-6652 2908);
FORCEPROP 2 LAST CDS_LIB mstr_standard
J 0
(-6650 2900);
DISPLAY INVISIBLE (-6650 2900);
FORCEPROP 1 LAST BODY_TYPE PLUMBING
J 0
(-6650 2850);
DISPLAY 0.574468 (-6650 2850);
PAINT GREEN (-6650 2850);
DISPLAY INVISIBLE (-6650 2850);
FORCEPROP 1 LAST HDL_TAP TRUE
J 0
(-6325 2775);
DISPLAY 0.574468 (-6325 2775);
PAINT GREEN (-6325 2775);
DISPLAY INVISIBLE (-6325 2775);
FORCEPROP 1 LAST PATH I321
J 0
(-6652 2900);
DISPLAY 0.872340 (-6652 2900);
PAINT GREEN (-6652 2900);
DISPLAY INVISIBLE (-6652 2900);
FORCEADD TAP..6
(-6500 2750);
FORCEPROP 3 LASTPIN (-6450 2750) SIG_NAME P5E_CPU0_G3_RX_DP<2>
J 0
(-6440 2760);
DISPLAY 0.659574 (-6440 2760);
PAINT MONO (-6440 2760);
DISPLAY INVISIBLE (-6440 2760);
FORCEPROP 1 LASTPIN (-6450 2750) BN 2
J 0
(-6502 2758);
DISPLAY 0.489362 (-6502 2758);
PAINT MONO (-6502 2758);
FORCEPROP 2 LAST CDS_LIB mstr_standard
J 0
(-6500 2750);
DISPLAY INVISIBLE (-6500 2750);
FORCEPROP 1 LAST BODY_TYPE PLUMBING
J 0
(-6500 2700);
DISPLAY 0.574468 (-6500 2700);
PAINT GREEN (-6500 2700);
DISPLAY INVISIBLE (-6500 2700);
FORCEPROP 1 LAST HDL_TAP TRUE
J 0
(-6175 2625);
DISPLAY 0.574468 (-6175 2625);
PAINT GREEN (-6175 2625);
DISPLAY INVISIBLE (-6175 2625);
FORCEPROP 1 LAST PATH I322
J 0
(-6502 2750);
DISPLAY 0.872340 (-6502 2750);
PAINT GREEN (-6502 2750);
DISPLAY INVISIBLE (-6502 2750);
FORCEADD TAP..6
(-6500 2650);
FORCEPROP 3 LASTPIN (-6450 2650) SIG_NAME P5E_CPU0_G3_RX_DP<3>
J 0
(-6440 2660);
DISPLAY 0.659574 (-6440 2660);
PAINT MONO (-6440 2660);
DISPLAY INVISIBLE (-6440 2660);
FORCEPROP 1 LASTPIN (-6450 2650) BN 3
J 0
(-6502 2658);
DISPLAY 0.489362 (-6502 2658);
PAINT MONO (-6502 2658);
FORCEPROP 2 LAST CDS_LIB standard
J 0
(-6500 2650);
DISPLAY INVISIBLE (-6500 2650);
FORCEPROP 1 LAST BODY_TYPE PLUMBING
J 0
(-6500 2600);
DISPLAY 0.574468 (-6500 2600);
PAINT GREEN (-6500 2600);
DISPLAY INVISIBLE (-6500 2600);
FORCEPROP 1 LAST HDL_TAP TRUE
J 0
(-6175 2525);
DISPLAY 0.574468 (-6175 2525);
PAINT GREEN (-6175 2525);
DISPLAY INVISIBLE (-6175 2525);
FORCEPROP 1 LAST PATH I323
J 0
(-6502 2650);
DISPLAY 0.872340 (-6502 2650);
PAINT GREEN (-6502 2650);
DISPLAY INVISIBLE (-6502 2650);
FORCEADD TAP..6
(-6650 2800);
FORCEPROP 3 LASTPIN (-6600 2800) SIG_NAME P5E_CPU0_G3_RX_DN<1>
J 0
(-6590 2810);
DISPLAY 0.659574 (-6590 2810);
PAINT MONO (-6590 2810);
DISPLAY INVISIBLE (-6590 2810);
FORCEPROP 1 LASTPIN (-6600 2800) BN 1
J 0
(-6652 2808);
DISPLAY 0.489362 (-6652 2808);
PAINT MONO (-6652 2808);
FORCEPROP 2 LAST CDS_LIB mstr_standard
J 0
(-6650 2800);
DISPLAY INVISIBLE (-6650 2800);
FORCEPROP 1 LAST BODY_TYPE PLUMBING
J 0
(-6650 2750);
DISPLAY 0.574468 (-6650 2750);
PAINT GREEN (-6650 2750);
DISPLAY INVISIBLE (-6650 2750);
FORCEPROP 1 LAST HDL_TAP TRUE
J 0
(-6325 2675);
DISPLAY 0.574468 (-6325 2675);
PAINT GREEN (-6325 2675);
DISPLAY INVISIBLE (-6325 2675);
FORCEPROP 1 LAST PATH I324
J 0
(-6652 2800);
DISPLAY 0.872340 (-6652 2800);
PAINT GREEN (-6652 2800);
DISPLAY INVISIBLE (-6652 2800);
FORCEADD TAP..6
(-6650 2700);
FORCEPROP 3 LASTPIN (-6600 2700) SIG_NAME P5E_CPU0_G3_RX_DN<2>
J 0
(-6590 2710);
DISPLAY 0.659574 (-6590 2710);
PAINT MONO (-6590 2710);
DISPLAY INVISIBLE (-6590 2710);
FORCEPROP 1 LASTPIN (-6600 2700) BN 2
J 0
(-6652 2708);
DISPLAY 0.489362 (-6652 2708);
PAINT MONO (-6652 2708);
FORCEPROP 2 LAST CDS_LIB standard
J 0
(-6650 2700);
DISPLAY INVISIBLE (-6650 2700);
FORCEPROP 1 LAST BODY_TYPE PLUMBING
J 0
(-6650 2650);
DISPLAY 0.574468 (-6650 2650);
PAINT GREEN (-6650 2650);
DISPLAY INVISIBLE (-6650 2650);
FORCEPROP 1 LAST HDL_TAP TRUE
J 0
(-6325 2575);
DISPLAY 0.574468 (-6325 2575);
PAINT GREEN (-6325 2575);
DISPLAY INVISIBLE (-6325 2575);
FORCEPROP 1 LAST PATH I325
J 0
(-6652 2700);
DISPLAY 0.872340 (-6652 2700);
PAINT GREEN (-6652 2700);
DISPLAY INVISIBLE (-6652 2700);
FORCEADD TAP..6
(-6650 2600);
FORCEPROP 3 LASTPIN (-6600 2600) SIG_NAME P5E_CPU0_G3_RX_DN<3>
J 0
(-6590 2610);
DISPLAY 0.659574 (-6590 2610);
PAINT MONO (-6590 2610);
DISPLAY INVISIBLE (-6590 2610);
FORCEPROP 1 LASTPIN (-6600 2600) BN 3
J 0
(-6652 2608);
DISPLAY 0.489362 (-6652 2608);
PAINT MONO (-6652 2608);
FORCEPROP 2 LAST CDS_LIB standard
J 0
(-6650 2600);
DISPLAY INVISIBLE (-6650 2600);
FORCEPROP 1 LAST BODY_TYPE PLUMBING
J 0
(-6650 2550);
DISPLAY 0.574468 (-6650 2550);
PAINT GREEN (-6650 2550);
DISPLAY INVISIBLE (-6650 2550);
FORCEPROP 1 LAST HDL_TAP TRUE
J 0
(-6325 2475);
DISPLAY 0.574468 (-6325 2475);
PAINT GREEN (-6325 2475);
DISPLAY INVISIBLE (-6325 2475);
FORCEPROP 1 LAST PATH I326
J 0
(-6652 2600);
DISPLAY 0.872340 (-6652 2600);
PAINT GREEN (-6652 2600);
DISPLAY INVISIBLE (-6652 2600);
FORCEADD TAP..6
(-6500 2550);
FORCEPROP 3 LASTPIN (-6450 2550) SIG_NAME P5E_CPU0_G3_RX_DP<4>
J 0
(-6440 2560);
DISPLAY 0.659574 (-6440 2560);
PAINT MONO (-6440 2560);
DISPLAY INVISIBLE (-6440 2560);
FORCEPROP 1 LASTPIN (-6450 2550) BN 4
J 0
(-6502 2558);
DISPLAY 0.489362 (-6502 2558);
PAINT MONO (-6502 2558);
FORCEPROP 2 LAST CDS_LIB standard
J 0
(-6500 2550);
DISPLAY INVISIBLE (-6500 2550);
FORCEPROP 1 LAST BODY_TYPE PLUMBING
J 0
(-6500 2500);
DISPLAY 0.574468 (-6500 2500);
PAINT GREEN (-6500 2500);
DISPLAY INVISIBLE (-6500 2500);
FORCEPROP 1 LAST HDL_TAP TRUE
J 0
(-6175 2425);
DISPLAY 0.574468 (-6175 2425);
PAINT GREEN (-6175 2425);
DISPLAY INVISIBLE (-6175 2425);
FORCEPROP 1 LAST PATH I327
J 0
(-6502 2550);
DISPLAY 0.872340 (-6502 2550);
PAINT GREEN (-6502 2550);
DISPLAY INVISIBLE (-6502 2550);
FORCEADD TAP..6
(-6500 2450);
FORCEPROP 3 LASTPIN (-6450 2450) SIG_NAME P5E_CPU0_G3_RX_DP<5>
J 0
(-6440 2460);
DISPLAY 0.659574 (-6440 2460);
PAINT MONO (-6440 2460);
DISPLAY INVISIBLE (-6440 2460);
FORCEPROP 1 LASTPIN (-6450 2450) BN 5
J 0
(-6502 2458);
DISPLAY 0.489362 (-6502 2458);
PAINT MONO (-6502 2458);
FORCEPROP 2 LAST CDS_LIB standard
J 0
(-6500 2450);
DISPLAY INVISIBLE (-6500 2450);
FORCEPROP 1 LAST BODY_TYPE PLUMBING
J 0
(-6500 2400);
DISPLAY 0.574468 (-6500 2400);
PAINT GREEN (-6500 2400);
DISPLAY INVISIBLE (-6500 2400);
FORCEPROP 1 LAST HDL_TAP TRUE
J 0
(-6175 2325);
DISPLAY 0.574468 (-6175 2325);
PAINT GREEN (-6175 2325);
DISPLAY INVISIBLE (-6175 2325);
FORCEPROP 1 LAST PATH I328
J 0
(-6502 2450);
DISPLAY 0.872340 (-6502 2450);
PAINT GREEN (-6502 2450);
DISPLAY INVISIBLE (-6502 2450);
FORCEADD TAP..6
(-6500 2350);
FORCEPROP 3 LASTPIN (-6450 2350) SIG_NAME P5E_CPU0_G3_RX_DP<6>
J 0
(-6440 2360);
DISPLAY 0.659574 (-6440 2360);
PAINT MONO (-6440 2360);
DISPLAY INVISIBLE (-6440 2360);
FORCEPROP 1 LASTPIN (-6450 2350) BN 6
J 0
(-6502 2358);
DISPLAY 0.489362 (-6502 2358);
PAINT MONO (-6502 2358);
FORCEPROP 2 LAST CDS_LIB standard
J 0
(-6500 2350);
DISPLAY INVISIBLE (-6500 2350);
FORCEPROP 1 LAST BODY_TYPE PLUMBING
J 0
(-6500 2300);
DISPLAY 0.574468 (-6500 2300);
PAINT GREEN (-6500 2300);
DISPLAY INVISIBLE (-6500 2300);
FORCEPROP 1 LAST HDL_TAP TRUE
J 0
(-6175 2225);
DISPLAY 0.574468 (-6175 2225);
PAINT GREEN (-6175 2225);
DISPLAY INVISIBLE (-6175 2225);
FORCEPROP 1 LAST PATH I329
J 0
(-6502 2350);
DISPLAY 0.872340 (-6502 2350);
PAINT GREEN (-6502 2350);
DISPLAY INVISIBLE (-6502 2350);
FORCEADD TAP..6
(-6650 2500);
FORCEPROP 3 LASTPIN (-6600 2500) SIG_NAME P5E_CPU0_G3_RX_DN<4>
J 0
(-6590 2510);
DISPLAY 0.659574 (-6590 2510);
PAINT MONO (-6590 2510);
DISPLAY INVISIBLE (-6590 2510);
FORCEPROP 1 LASTPIN (-6600 2500) BN 4
J 0
(-6652 2508);
DISPLAY 0.489362 (-6652 2508);
PAINT MONO (-6652 2508);
FORCEPROP 2 LAST CDS_LIB standard
J 0
(-6650 2500);
DISPLAY INVISIBLE (-6650 2500);
FORCEPROP 1 LAST BODY_TYPE PLUMBING
J 0
(-6650 2450);
DISPLAY 0.574468 (-6650 2450);
PAINT GREEN (-6650 2450);
DISPLAY INVISIBLE (-6650 2450);
FORCEPROP 1 LAST HDL_TAP TRUE
J 0
(-6325 2375);
DISPLAY 0.574468 (-6325 2375);
PAINT GREEN (-6325 2375);
DISPLAY INVISIBLE (-6325 2375);
FORCEPROP 1 LAST PATH I330
J 0
(-6652 2500);
DISPLAY 0.872340 (-6652 2500);
PAINT GREEN (-6652 2500);
DISPLAY INVISIBLE (-6652 2500);
FORCEADD TAP..6
(-6650 2400);
FORCEPROP 3 LASTPIN (-6600 2400) SIG_NAME P5E_CPU0_G3_RX_DN<5>
J 0
(-6590 2410);
DISPLAY 0.659574 (-6590 2410);
PAINT MONO (-6590 2410);
DISPLAY INVISIBLE (-6590 2410);
FORCEPROP 1 LASTPIN (-6600 2400) BN 5
J 0
(-6652 2408);
DISPLAY 0.489362 (-6652 2408);
PAINT MONO (-6652 2408);
FORCEPROP 2 LAST CDS_LIB standard
J 0
(-6650 2400);
DISPLAY INVISIBLE (-6650 2400);
FORCEPROP 1 LAST BODY_TYPE PLUMBING
J 0
(-6650 2350);
DISPLAY 0.574468 (-6650 2350);
PAINT GREEN (-6650 2350);
DISPLAY INVISIBLE (-6650 2350);
FORCEPROP 1 LAST HDL_TAP TRUE
J 0
(-6325 2275);
DISPLAY 0.574468 (-6325 2275);
PAINT GREEN (-6325 2275);
DISPLAY INVISIBLE (-6325 2275);
FORCEPROP 1 LAST PATH I331
J 0
(-6652 2400);
DISPLAY 0.872340 (-6652 2400);
PAINT GREEN (-6652 2400);
DISPLAY INVISIBLE (-6652 2400);
FORCEADD TAP..6
(-6500 2250);
FORCEPROP 3 LASTPIN (-6450 2250) SIG_NAME P5E_CPU0_G3_RX_DP<7>
J 0
(-6440 2260);
DISPLAY 0.659574 (-6440 2260);
PAINT MONO (-6440 2260);
DISPLAY INVISIBLE (-6440 2260);
FORCEPROP 1 LASTPIN (-6450 2250) BN 7
J 0
(-6502 2258);
DISPLAY 0.489362 (-6502 2258);
PAINT MONO (-6502 2258);
FORCEPROP 2 LAST CDS_LIB standard
J 0
(-6500 2250);
DISPLAY INVISIBLE (-6500 2250);
FORCEPROP 1 LAST BODY_TYPE PLUMBING
J 0
(-6500 2200);
DISPLAY 0.574468 (-6500 2200);
PAINT GREEN (-6500 2200);
DISPLAY INVISIBLE (-6500 2200);
FORCEPROP 1 LAST HDL_TAP TRUE
J 0
(-6175 2125);
DISPLAY 0.574468 (-6175 2125);
PAINT GREEN (-6175 2125);
DISPLAY INVISIBLE (-6175 2125);
FORCEPROP 1 LAST PATH I332
J 0
(-6502 2250);
DISPLAY 0.872340 (-6502 2250);
PAINT GREEN (-6502 2250);
DISPLAY INVISIBLE (-6502 2250);
FORCEADD TAP..6
(-6500 2150);
FORCEPROP 3 LASTPIN (-6450 2150) SIG_NAME P5E_CPU0_G3_RX_DP<8>
J 0
(-6440 2160);
DISPLAY 0.659574 (-6440 2160);
PAINT MONO (-6440 2160);
DISPLAY INVISIBLE (-6440 2160);
FORCEPROP 1 LASTPIN (-6450 2150) BN 8
J 0
(-6502 2158);
DISPLAY 0.489362 (-6502 2158);
PAINT MONO (-6502 2158);
FORCEPROP 2 LAST CDS_LIB standard
J 0
(-6500 2150);
DISPLAY INVISIBLE (-6500 2150);
FORCEPROP 1 LAST BODY_TYPE PLUMBING
J 0
(-6500 2100);
DISPLAY 0.574468 (-6500 2100);
PAINT GREEN (-6500 2100);
DISPLAY INVISIBLE (-6500 2100);
FORCEPROP 1 LAST HDL_TAP TRUE
J 0
(-6175 2025);
DISPLAY 0.574468 (-6175 2025);
PAINT GREEN (-6175 2025);
DISPLAY INVISIBLE (-6175 2025);
FORCEPROP 1 LAST PATH I333
J 0
(-6502 2150);
DISPLAY 0.872340 (-6502 2150);
PAINT GREEN (-6502 2150);
DISPLAY INVISIBLE (-6502 2150);
FORCEADD TAP..6
(-6500 2050);
FORCEPROP 3 LASTPIN (-6450 2050) SIG_NAME P5E_CPU0_G3_RX_DP<9>
J 0
(-6440 2060);
DISPLAY 0.659574 (-6440 2060);
PAINT MONO (-6440 2060);
DISPLAY INVISIBLE (-6440 2060);
FORCEPROP 1 LASTPIN (-6450 2050) BN 9
J 0
(-6502 2058);
DISPLAY 0.489362 (-6502 2058);
PAINT MONO (-6502 2058);
FORCEPROP 2 LAST CDS_LIB standard
J 0
(-6500 2050);
DISPLAY INVISIBLE (-6500 2050);
FORCEPROP 1 LAST BODY_TYPE PLUMBING
J 0
(-6500 2000);
DISPLAY 0.574468 (-6500 2000);
PAINT GREEN (-6500 2000);
DISPLAY INVISIBLE (-6500 2000);
FORCEPROP 1 LAST HDL_TAP TRUE
J 0
(-6175 1925);
DISPLAY 0.574468 (-6175 1925);
PAINT GREEN (-6175 1925);
DISPLAY INVISIBLE (-6175 1925);
FORCEPROP 1 LAST PATH I334
J 0
(-6502 2050);
DISPLAY 0.872340 (-6502 2050);
PAINT GREEN (-6502 2050);
DISPLAY INVISIBLE (-6502 2050);
FORCEADD TAP..6
(-6650 2300);
FORCEPROP 3 LASTPIN (-6600 2300) SIG_NAME P5E_CPU0_G3_RX_DN<6>
J 0
(-6590 2310);
DISPLAY 0.659574 (-6590 2310);
PAINT MONO (-6590 2310);
DISPLAY INVISIBLE (-6590 2310);
FORCEPROP 1 LASTPIN (-6600 2300) BN 6
J 0
(-6652 2308);
DISPLAY 0.489362 (-6652 2308);
PAINT MONO (-6652 2308);
FORCEPROP 2 LAST CDS_LIB standard
J 0
(-6650 2300);
DISPLAY INVISIBLE (-6650 2300);
FORCEPROP 1 LAST BODY_TYPE PLUMBING
J 0
(-6650 2250);
DISPLAY 0.574468 (-6650 2250);
PAINT GREEN (-6650 2250);
DISPLAY INVISIBLE (-6650 2250);
FORCEPROP 1 LAST HDL_TAP TRUE
J 0
(-6325 2175);
DISPLAY 0.574468 (-6325 2175);
PAINT GREEN (-6325 2175);
DISPLAY INVISIBLE (-6325 2175);
FORCEPROP 1 LAST PATH I335
J 0
(-6652 2300);
DISPLAY 0.872340 (-6652 2300);
PAINT GREEN (-6652 2300);
DISPLAY INVISIBLE (-6652 2300);
FORCEADD TAP..6
(-6650 2200);
FORCEPROP 3 LASTPIN (-6600 2200) SIG_NAME P5E_CPU0_G3_RX_DN<7>
J 0
(-6590 2210);
DISPLAY 0.659574 (-6590 2210);
PAINT MONO (-6590 2210);
DISPLAY INVISIBLE (-6590 2210);
FORCEPROP 1 LASTPIN (-6600 2200) BN 7
J 0
(-6652 2208);
DISPLAY 0.489362 (-6652 2208);
PAINT MONO (-6652 2208);
FORCEPROP 2 LAST CDS_LIB standard
J 0
(-6650 2200);
DISPLAY INVISIBLE (-6650 2200);
FORCEPROP 1 LAST BODY_TYPE PLUMBING
J 0
(-6650 2150);
DISPLAY 0.574468 (-6650 2150);
PAINT GREEN (-6650 2150);
DISPLAY INVISIBLE (-6650 2150);
FORCEPROP 1 LAST HDL_TAP TRUE
J 0
(-6325 2075);
DISPLAY 0.574468 (-6325 2075);
PAINT GREEN (-6325 2075);
DISPLAY INVISIBLE (-6325 2075);
FORCEPROP 1 LAST PATH I336
J 0
(-6652 2200);
DISPLAY 0.872340 (-6652 2200);
PAINT GREEN (-6652 2200);
DISPLAY INVISIBLE (-6652 2200);
FORCEADD TAP..6
(-6650 2100);
FORCEPROP 3 LASTPIN (-6600 2100) SIG_NAME P5E_CPU0_G3_RX_DN<8>
J 0
(-6590 2110);
DISPLAY 0.659574 (-6590 2110);
PAINT MONO (-6590 2110);
DISPLAY INVISIBLE (-6590 2110);
FORCEPROP 1 LASTPIN (-6600 2100) BN 8
J 0
(-6652 2108);
DISPLAY 0.489362 (-6652 2108);
PAINT MONO (-6652 2108);
FORCEPROP 2 LAST CDS_LIB standard
J 0
(-6650 2100);
DISPLAY INVISIBLE (-6650 2100);
FORCEPROP 1 LAST BODY_TYPE PLUMBING
J 0
(-6650 2050);
DISPLAY 0.574468 (-6650 2050);
PAINT GREEN (-6650 2050);
DISPLAY INVISIBLE (-6650 2050);
FORCEPROP 1 LAST HDL_TAP TRUE
J 0
(-6325 1975);
DISPLAY 0.574468 (-6325 1975);
PAINT GREEN (-6325 1975);
DISPLAY INVISIBLE (-6325 1975);
FORCEPROP 1 LAST PATH I337
J 0
(-6652 2100);
DISPLAY 0.872340 (-6652 2100);
PAINT GREEN (-6652 2100);
DISPLAY INVISIBLE (-6652 2100);
FORCEADD OFFPAGE..1
(-7700 3175);
FORCEPROP 2 LASTPIN (-7650 3175) SIG_NAME P5E_CPU0_G3_RX_DP<15:0>
J 0
(-7635 3185);
DISPLAY 0.489362 (-7635 3185);
FORCEPROP 2 LAST CDS_LIB standard
J 0
(-7700 3175);
DISPLAY INVISIBLE (-7700 3175);
FORCEPROP 1 LAST OFFPAGE TRUE
J 0
(-7375 3050);
DISPLAY 0.872340 (-7375 3050);
PAINT GREEN (-7375 3050);
DISPLAY INVISIBLE (-7375 3050);
FORCEPROP 1 LAST COMMENT_BODY TRUE
J 0
(-7575 3075);
DISPLAY 0.872340 (-7575 3075);
PAINT GREEN (-7575 3075);
DISPLAY INVISIBLE (-7575 3075);
FORCEPROP 2 LAST PATH I338
J 0
(-7900 3225);
DISPLAY 1.021277 (-7900 3225);
DISPLAY INVISIBLE (-7900 3225);
FORCEADD OFFPAGE..1
(-7700 3125);
FORCEPROP 2 LASTPIN (-7650 3125) SIG_NAME P5E_CPU0_G3_RX_DN<15:0>
J 0
(-7635 3135);
DISPLAY 0.489362 (-7635 3135);
FORCEPROP 2 LAST CDS_LIB standard
J 0
(-7700 3125);
DISPLAY INVISIBLE (-7700 3125);
FORCEPROP 1 LAST OFFPAGE TRUE
J 0
(-7375 3000);
DISPLAY 0.872340 (-7375 3000);
PAINT GREEN (-7375 3000);
DISPLAY INVISIBLE (-7375 3000);
FORCEPROP 1 LAST COMMENT_BODY TRUE
J 0
(-7575 3025);
DISPLAY 0.872340 (-7575 3025);
PAINT GREEN (-7575 3025);
DISPLAY INVISIBLE (-7575 3025);
FORCEPROP 2 LAST PATH I339
J 0
(-7900 3175);
DISPLAY 1.021277 (-7900 3175);
DISPLAY INVISIBLE (-7900 3175);
FORCEADD TAP..6
(-6500 1950);
FORCEPROP 3 LASTPIN (-6450 1950) SIG_NAME P5E_CPU0_G3_RX_DP<10>
J 0
(-6440 1960);
DISPLAY 0.659574 (-6440 1960);
PAINT MONO (-6440 1960);
DISPLAY INVISIBLE (-6440 1960);
FORCEPROP 1 LASTPIN (-6450 1950) BN 10
J 0
(-6502 1958);
DISPLAY 0.489362 (-6502 1958);
PAINT MONO (-6502 1958);
FORCEPROP 2 LAST CDS_LIB standard
J 0
(-6500 1950);
DISPLAY INVISIBLE (-6500 1950);
FORCEPROP 1 LAST BODY_TYPE PLUMBING
J 0
(-6500 1900);
DISPLAY 0.574468 (-6500 1900);
PAINT GREEN (-6500 1900);
DISPLAY INVISIBLE (-6500 1900);
FORCEPROP 1 LAST HDL_TAP TRUE
J 0
(-6175 1825);
DISPLAY 0.574468 (-6175 1825);
PAINT GREEN (-6175 1825);
DISPLAY INVISIBLE (-6175 1825);
FORCEPROP 1 LAST PATH I340
J 0
(-6502 1950);
DISPLAY 0.872340 (-6502 1950);
PAINT GREEN (-6502 1950);
DISPLAY INVISIBLE (-6502 1950);
FORCEADD TAP..6
(-6500 1850);
FORCEPROP 3 LASTPIN (-6450 1850) SIG_NAME P5E_CPU0_G3_RX_DP<11>
J 0
(-6440 1860);
DISPLAY 0.659574 (-6440 1860);
PAINT MONO (-6440 1860);
DISPLAY INVISIBLE (-6440 1860);
FORCEPROP 1 LASTPIN (-6450 1850) BN 11
J 0
(-6502 1858);
DISPLAY 0.489362 (-6502 1858);
PAINT MONO (-6502 1858);
FORCEPROP 2 LAST CDS_LIB standard
J 0
(-6500 1850);
DISPLAY INVISIBLE (-6500 1850);
FORCEPROP 1 LAST BODY_TYPE PLUMBING
J 0
(-6500 1800);
DISPLAY 0.574468 (-6500 1800);
PAINT GREEN (-6500 1800);
DISPLAY INVISIBLE (-6500 1800);
FORCEPROP 1 LAST HDL_TAP TRUE
J 0
(-6175 1725);
DISPLAY 0.574468 (-6175 1725);
PAINT GREEN (-6175 1725);
DISPLAY INVISIBLE (-6175 1725);
FORCEPROP 1 LAST PATH I341
J 0
(-6502 1850);
DISPLAY 0.872340 (-6502 1850);
PAINT GREEN (-6502 1850);
DISPLAY INVISIBLE (-6502 1850);
FORCEADD TAP..6
(-6650 2000);
FORCEPROP 3 LASTPIN (-6600 2000) SIG_NAME P5E_CPU0_G3_RX_DN<9>
J 0
(-6590 2010);
DISPLAY 0.659574 (-6590 2010);
PAINT MONO (-6590 2010);
DISPLAY INVISIBLE (-6590 2010);
FORCEPROP 1 LASTPIN (-6600 2000) BN 9
J 0
(-6652 2008);
DISPLAY 0.489362 (-6652 2008);
PAINT MONO (-6652 2008);
FORCEPROP 2 LAST CDS_LIB standard
J 0
(-6650 2000);
DISPLAY INVISIBLE (-6650 2000);
FORCEPROP 1 LAST BODY_TYPE PLUMBING
J 0
(-6650 1950);
DISPLAY 0.574468 (-6650 1950);
PAINT GREEN (-6650 1950);
DISPLAY INVISIBLE (-6650 1950);
FORCEPROP 1 LAST HDL_TAP TRUE
J 0
(-6325 1875);
DISPLAY 0.574468 (-6325 1875);
PAINT GREEN (-6325 1875);
DISPLAY INVISIBLE (-6325 1875);
FORCEPROP 1 LAST PATH I342
J 0
(-6652 2000);
DISPLAY 0.872340 (-6652 2000);
PAINT GREEN (-6652 2000);
DISPLAY INVISIBLE (-6652 2000);
FORCEADD TAP..6
(-6650 1900);
FORCEPROP 3 LASTPIN (-6600 1900) SIG_NAME P5E_CPU0_G3_RX_DN<10>
J 0
(-6590 1910);
DISPLAY 0.659574 (-6590 1910);
PAINT MONO (-6590 1910);
DISPLAY INVISIBLE (-6590 1910);
FORCEPROP 1 LASTPIN (-6600 1900) BN 10
J 0
(-6652 1908);
DISPLAY 0.489362 (-6652 1908);
PAINT MONO (-6652 1908);
FORCEPROP 2 LAST CDS_LIB standard
J 0
(-6650 1900);
DISPLAY INVISIBLE (-6650 1900);
FORCEPROP 1 LAST BODY_TYPE PLUMBING
J 0
(-6650 1850);
DISPLAY 0.574468 (-6650 1850);
PAINT GREEN (-6650 1850);
DISPLAY INVISIBLE (-6650 1850);
FORCEPROP 1 LAST HDL_TAP TRUE
J 0
(-6325 1775);
DISPLAY 0.574468 (-6325 1775);
PAINT GREEN (-6325 1775);
DISPLAY INVISIBLE (-6325 1775);
FORCEPROP 1 LAST PATH I343
J 0
(-6652 1900);
DISPLAY 0.872340 (-6652 1900);
PAINT GREEN (-6652 1900);
DISPLAY INVISIBLE (-6652 1900);
FORCEADD TAP..6
(-6650 1800);
FORCEPROP 3 LASTPIN (-6600 1800) SIG_NAME P5E_CPU0_G3_RX_DN<11>
J 0
(-6590 1810);
DISPLAY 0.659574 (-6590 1810);
PAINT MONO (-6590 1810);
DISPLAY INVISIBLE (-6590 1810);
FORCEPROP 1 LASTPIN (-6600 1800) BN 11
J 0
(-6652 1808);
DISPLAY 0.489362 (-6652 1808);
PAINT MONO (-6652 1808);
FORCEPROP 2 LAST CDS_LIB standard
J 0
(-6650 1800);
DISPLAY INVISIBLE (-6650 1800);
FORCEPROP 1 LAST BODY_TYPE PLUMBING
J 0
(-6650 1750);
DISPLAY 0.574468 (-6650 1750);
PAINT GREEN (-6650 1750);
DISPLAY INVISIBLE (-6650 1750);
FORCEPROP 1 LAST HDL_TAP TRUE
J 0
(-6325 1675);
DISPLAY 0.574468 (-6325 1675);
PAINT GREEN (-6325 1675);
DISPLAY INVISIBLE (-6325 1675);
FORCEPROP 1 LAST PATH I344
J 0
(-6652 1800);
DISPLAY 0.872340 (-6652 1800);
PAINT GREEN (-6652 1800);
DISPLAY INVISIBLE (-6652 1800);
FORCEADD TAP..6
(-6500 1650);
FORCEPROP 3 LASTPIN (-6450 1650) SIG_NAME P5E_CPU0_G3_RX_DP<13>
J 0
(-6440 1660);
DISPLAY 0.659574 (-6440 1660);
PAINT MONO (-6440 1660);
DISPLAY INVISIBLE (-6440 1660);
FORCEPROP 1 LASTPIN (-6450 1650) BN 13
J 0
(-6502 1658);
DISPLAY 0.489362 (-6502 1658);
PAINT MONO (-6502 1658);
FORCEPROP 2 LAST CDS_LIB standard
J 0
(-6500 1650);
DISPLAY INVISIBLE (-6500 1650);
FORCEPROP 1 LAST BODY_TYPE PLUMBING
J 0
(-6500 1600);
DISPLAY 0.574468 (-6500 1600);
PAINT GREEN (-6500 1600);
DISPLAY INVISIBLE (-6500 1600);
FORCEPROP 1 LAST HDL_TAP TRUE
J 0
(-6175 1525);
DISPLAY 0.574468 (-6175 1525);
PAINT GREEN (-6175 1525);
DISPLAY INVISIBLE (-6175 1525);
FORCEPROP 1 LAST PATH I345
J 0
(-6502 1650);
DISPLAY 0.872340 (-6502 1650);
PAINT GREEN (-6502 1650);
DISPLAY INVISIBLE (-6502 1650);
FORCEADD TAP..6
(-6500 1750);
FORCEPROP 3 LASTPIN (-6450 1750) SIG_NAME P5E_CPU0_G3_RX_DP<12>
J 0
(-6440 1760);
DISPLAY 0.659574 (-6440 1760);
PAINT MONO (-6440 1760);
DISPLAY INVISIBLE (-6440 1760);
FORCEPROP 1 LASTPIN (-6450 1750) BN 12
J 0
(-6502 1758);
DISPLAY 0.489362 (-6502 1758);
PAINT MONO (-6502 1758);
FORCEPROP 2 LAST CDS_LIB standard
J 0
(-6500 1750);
DISPLAY INVISIBLE (-6500 1750);
FORCEPROP 1 LAST BODY_TYPE PLUMBING
J 0
(-6500 1700);
DISPLAY 0.574468 (-6500 1700);
PAINT GREEN (-6500 1700);
DISPLAY INVISIBLE (-6500 1700);
FORCEPROP 1 LAST HDL_TAP TRUE
J 0
(-6175 1625);
DISPLAY 0.574468 (-6175 1625);
PAINT GREEN (-6175 1625);
DISPLAY INVISIBLE (-6175 1625);
FORCEPROP 1 LAST PATH I346
J 0
(-6502 1750);
DISPLAY 0.872340 (-6502 1750);
PAINT GREEN (-6502 1750);
DISPLAY INVISIBLE (-6502 1750);
FORCEADD TAP..6
(-6500 1550);
FORCEPROP 3 LASTPIN (-6450 1550) SIG_NAME P5E_CPU0_G3_RX_DP<14>
J 0
(-6440 1560);
DISPLAY 0.659574 (-6440 1560);
PAINT MONO (-6440 1560);
DISPLAY INVISIBLE (-6440 1560);
FORCEPROP 1 LASTPIN (-6450 1550) BN 14
J 0
(-6502 1558);
DISPLAY 0.489362 (-6502 1558);
PAINT MONO (-6502 1558);
FORCEPROP 2 LAST CDS_LIB standard
J 0
(-6500 1550);
DISPLAY INVISIBLE (-6500 1550);
FORCEPROP 1 LAST BODY_TYPE PLUMBING
J 0
(-6500 1500);
DISPLAY 0.574468 (-6500 1500);
PAINT GREEN (-6500 1500);
DISPLAY INVISIBLE (-6500 1500);
FORCEPROP 1 LAST HDL_TAP TRUE
J 0
(-6175 1425);
DISPLAY 0.574468 (-6175 1425);
PAINT GREEN (-6175 1425);
DISPLAY INVISIBLE (-6175 1425);
FORCEPROP 1 LAST PATH I347
J 0
(-6502 1550);
DISPLAY 0.872340 (-6502 1550);
PAINT GREEN (-6502 1550);
DISPLAY INVISIBLE (-6502 1550);
FORCEADD TAP..6
(-6650 1700);
FORCEPROP 3 LASTPIN (-6600 1700) SIG_NAME P5E_CPU0_G3_RX_DN<12>
J 0
(-6590 1710);
DISPLAY 0.659574 (-6590 1710);
PAINT MONO (-6590 1710);
DISPLAY INVISIBLE (-6590 1710);
FORCEPROP 1 LASTPIN (-6600 1700) BN 12
J 0
(-6652 1708);
DISPLAY 0.489362 (-6652 1708);
PAINT MONO (-6652 1708);
FORCEPROP 2 LAST CDS_LIB standard
J 0
(-6650 1700);
DISPLAY INVISIBLE (-6650 1700);
FORCEPROP 1 LAST BODY_TYPE PLUMBING
J 0
(-6650 1650);
DISPLAY 0.574468 (-6650 1650);
PAINT GREEN (-6650 1650);
DISPLAY INVISIBLE (-6650 1650);
FORCEPROP 1 LAST HDL_TAP TRUE
J 0
(-6325 1575);
DISPLAY 0.574468 (-6325 1575);
PAINT GREEN (-6325 1575);
DISPLAY INVISIBLE (-6325 1575);
FORCEPROP 1 LAST PATH I348
J 0
(-6652 1700);
DISPLAY 0.872340 (-6652 1700);
PAINT GREEN (-6652 1700);
DISPLAY INVISIBLE (-6652 1700);
FORCEADD TAP..6
(-6650 1600);
FORCEPROP 3 LASTPIN (-6600 1600) SIG_NAME P5E_CPU0_G3_RX_DN<13>
J 0
(-6590 1610);
DISPLAY 0.659574 (-6590 1610);
PAINT MONO (-6590 1610);
DISPLAY INVISIBLE (-6590 1610);
FORCEPROP 1 LASTPIN (-6600 1600) BN 13
J 0
(-6652 1608);
DISPLAY 0.489362 (-6652 1608);
PAINT MONO (-6652 1608);
FORCEPROP 2 LAST CDS_LIB standard
J 0
(-6650 1600);
DISPLAY INVISIBLE (-6650 1600);
FORCEPROP 1 LAST BODY_TYPE PLUMBING
J 0
(-6650 1550);
DISPLAY 0.574468 (-6650 1550);
PAINT GREEN (-6650 1550);
DISPLAY INVISIBLE (-6650 1550);
FORCEPROP 1 LAST HDL_TAP TRUE
J 0
(-6325 1475);
DISPLAY 0.574468 (-6325 1475);
PAINT GREEN (-6325 1475);
DISPLAY INVISIBLE (-6325 1475);
FORCEPROP 1 LAST PATH I349
J 0
(-6652 1600);
DISPLAY 0.872340 (-6652 1600);
PAINT GREEN (-6652 1600);
DISPLAY INVISIBLE (-6652 1600);
FORCEADD TAP..6
(-6500 1450);
FORCEPROP 3 LASTPIN (-6450 1450) SIG_NAME P5E_CPU0_G3_RX_DP<15>
J 0
(-6440 1460);
DISPLAY 0.659574 (-6440 1460);
PAINT MONO (-6440 1460);
DISPLAY INVISIBLE (-6440 1460);
FORCEPROP 1 LASTPIN (-6450 1450) BN 15
J 0
(-6502 1458);
DISPLAY 0.489362 (-6502 1458);
PAINT MONO (-6502 1458);
FORCEPROP 2 LAST CDS_LIB standard
J 0
(-6500 1450);
DISPLAY INVISIBLE (-6500 1450);
FORCEPROP 1 LAST BODY_TYPE PLUMBING
J 0
(-6500 1400);
DISPLAY 0.574468 (-6500 1400);
PAINT GREEN (-6500 1400);
DISPLAY INVISIBLE (-6500 1400);
FORCEPROP 1 LAST HDL_TAP TRUE
J 0
(-6175 1325);
DISPLAY 0.574468 (-6175 1325);
PAINT GREEN (-6175 1325);
DISPLAY INVISIBLE (-6175 1325);
FORCEPROP 1 LAST PATH I350
J 0
(-6502 1450);
DISPLAY 0.872340 (-6502 1450);
PAINT GREEN (-6502 1450);
DISPLAY INVISIBLE (-6502 1450);
FORCEADD TAP..6
(-6650 1500);
FORCEPROP 3 LASTPIN (-6600 1500) SIG_NAME P5E_CPU0_G3_RX_DN<14>
J 0
(-6590 1510);
DISPLAY 0.659574 (-6590 1510);
PAINT MONO (-6590 1510);
DISPLAY INVISIBLE (-6590 1510);
FORCEPROP 1 LASTPIN (-6600 1500) BN 14
J 0
(-6652 1508);
DISPLAY 0.489362 (-6652 1508);
PAINT MONO (-6652 1508);
FORCEPROP 2 LAST CDS_LIB standard
J 0
(-6650 1500);
DISPLAY INVISIBLE (-6650 1500);
FORCEPROP 1 LAST BODY_TYPE PLUMBING
J 0
(-6650 1450);
DISPLAY 0.574468 (-6650 1450);
PAINT GREEN (-6650 1450);
DISPLAY INVISIBLE (-6650 1450);
FORCEPROP 1 LAST HDL_TAP TRUE
J 0
(-6325 1375);
DISPLAY 0.574468 (-6325 1375);
PAINT GREEN (-6325 1375);
DISPLAY INVISIBLE (-6325 1375);
FORCEPROP 1 LAST PATH I351
J 0
(-6652 1500);
DISPLAY 0.872340 (-6652 1500);
PAINT GREEN (-6652 1500);
DISPLAY INVISIBLE (-6652 1500);
FORCEADD TAP..6
(-6650 1400);
FORCEPROP 3 LASTPIN (-6600 1400) SIG_NAME P5E_CPU0_G3_RX_DN<15>
J 0
(-6590 1410);
DISPLAY 0.659574 (-6590 1410);
PAINT MONO (-6590 1410);
DISPLAY INVISIBLE (-6590 1410);
FORCEPROP 1 LASTPIN (-6600 1400) BN 15
J 0
(-6652 1408);
DISPLAY 0.489362 (-6652 1408);
PAINT MONO (-6652 1408);
FORCEPROP 2 LAST CDS_LIB standard
J 0
(-6650 1400);
DISPLAY INVISIBLE (-6650 1400);
FORCEPROP 1 LAST BODY_TYPE PLUMBING
J 0
(-6650 1350);
DISPLAY 0.574468 (-6650 1350);
PAINT GREEN (-6650 1350);
DISPLAY INVISIBLE (-6650 1350);
FORCEPROP 1 LAST HDL_TAP TRUE
J 0
(-6325 1275);
DISPLAY 0.574468 (-6325 1275);
PAINT GREEN (-6325 1275);
DISPLAY INVISIBLE (-6325 1275);
FORCEPROP 1 LAST PATH I352
J 0
(-6652 1400);
DISPLAY 0.872340 (-6652 1400);
PAINT GREEN (-6652 1400);
DISPLAY INVISIBLE (-6652 1400);
FORCEADD QUANTA_TITLE_BLOCK_C..1
(-100 100);
FORCEPROP 0 LAST CDS_CON_LAST_MODIFIED Fri Mar 11 14:52:18 2022
J 0
(-1985 115);
DISPLAY INVISIBLE (-1985 115);
FORCEPROP 1 LAST CUSTOM_TXT_CDS <CON_LAST_MODIFIED>
J 0
(-1985 115);
DISPLAY 0.978723 (-1985 115);
FORCEPROP 2 LAST CUSTOM_TXT_CDS <XR_PAGE_TITLE>
J 0
(-7990 5350);
DISPLAY 0.638298 (-7990 5350);
PAINT PINK (-7990 5350);
DISPLAY INVISIBLE (-7990 5350);
FORCEPROP 1 LAST CUSTOM_TXT_CDS <NAME_2>
J 0
(-3275 150);
FORCEPROP 1 LAST CUSTOM_TXT_CDS <NAME_1>
J 0
(-3275 275);
FORCEPROP 1 LAST CUSTOM_TXT_CDS <Q_NUMBER>
J 0
(-1503 203);
DISPLAY 1.212766 (-1503 203);
FORCEPROP 1 LAST CUSTOM_TXT_CDS <Q_PROJ>
J 0
(-2482 202);
DISPLAY 1.212766 (-2482 202);
FORCEPROP 1 LAST CUSTOM_TXT_CDS <Q_REV>
J 0
(-284 203);
DISPLAY 1.212766 (-284 203);
FORCEPROP 1 LAST CUSTOM_TXT_CDS <CON_PAGE_NUM> OF <CON_TOTAL_PAGES>
J 0
(-546 118);
DISPLAY 0.978723 (-546 118);
FORCEPROP 1 LAST Q_DEPT BU9
J 1
(-3863 149);
DISPLAY 1.957447 (-3863 149);
PAINT GREEN (-3863 149);
FORCEPROP 1 LAST Q_TITLE CPU0 PCIE G2/G3
J 0
(-9425 125);
DISPLAY 2.446809 (-9425 125);
PAINT GREEN (-9425 125);
FORCEPROP 2 LAST PAGE_BORDER TRUE
J 0
(-7990 5350);
DISPLAY 0.638298 (-7990 5350);
PAINT PINK (-7990 5350);
DISPLAY INVISIBLE (-7990 5350);
FORCEPROP 1 LAST CDS_LMAN_SYM_OUTLINE -9475,6775,100,-125
J 0
(-100 100);
DISPLAY 0.468085 (-100 100);
PAINT GREEN (-100 100);
DISPLAY INVISIBLE (-100 100);
FORCEPROP 2 LAST CDS_LIB pure_quanta
J 0
(-100 100);
DISPLAY INVISIBLE (-100 100);
FORCEPROP 1 LAST COMMENT_BODY TRUE
J 0
(-88 87);
DISPLAY 0.978723 (-88 87);
PAINT GREEN (-88 87);
DISPLAY INVISIBLE (-88 87);
FORCEPROP 2 LAST CDS_XR_PAGE_TITLE CR-23 : @T6G_MB_LIB.T6G(SCH_1):PAGE23
J 0
(-7990 5350);
DISPLAY 0.638298 (-7990 5350);
PAINT PINK (-7990 5350);
DISPLAY INVISIBLE (-7990 5350);
WIRE 17 -1 (-6725 5300)(-6725 5400);
WIRE 17 -1 (-6725 5200)(-6725 5300);
WIRE 17 -1 (-6725 5400)(-6725 5500);
WIRE 17 -1 (-6725 5500)(-6725 5600);
WIRE 17 -1 (-6725 5100)(-6725 5200);
WIRE 17 -1 (-6725 5000)(-6725 5100);
WIRE 17 -1 (-6725 5600)(-6725 5700);
WIRE 17 -1 (-6725 5700)(-6725 5800);
WIRE 17 -1 (-6725 4900)(-6725 5000);
WIRE 17 -1 (-6725 4800)(-6725 4900);
WIRE 17 -1 (-6725 5800)(-6725 6000);
WIRE 17 -1 (-6725 6000)(-7675 6000);
FORCEPROP 2 LAST SIG_NAME GMI_CPU1_G0_CPU0_G2_TX_DN<15:0>
J 0
(-7635 6010);
DISPLAY 0.489362 (-7635 6010);
WIRE 17 -1 (-6575 5250)(-6575 5350);
WIRE 17 -1 (-6575 5150)(-6575 5250);
WIRE 17 -1 (-6575 5350)(-6575 5450);
WIRE 17 -1 (-6575 5450)(-6575 5550);
WIRE 17 -1 (-6575 5050)(-6575 5150);
WIRE 17 -1 (-6575 4950)(-6575 5050);
WIRE 17 -1 (-6575 5550)(-6575 5650);
WIRE 17 -1 (-6575 5650)(-6575 5750);
WIRE 17 -1 (-6575 4850)(-6575 4950);
WIRE 17 -1 (-6575 4750)(-6575 4850);
WIRE 17 -1 (-6575 5750)(-6575 5850);
WIRE 17 -1 (-6575 5850)(-6575 6050);
WIRE 17 -1 (-6575 4650)(-6575 4750);
WIRE 17 -1 (-6575 4550)(-6575 4650);
WIRE 17 -1 (-6575 6050)(-7675 6050);
FORCEPROP 2 LAST SIG_NAME GMI_CPU1_G0_CPU0_G2_TX_DP<15:0>
J 0
(-7635 6060);
DISPLAY 0.489362 (-7635 6060);
WIRE 17 -1 (-6725 4700)(-6725 4800);
WIRE 17 -1 (-6725 4600)(-6725 4700);
WIRE 17 -1 (-6725 4500)(-6725 4600);
WIRE 17 -1 (-6725 4400)(-6725 4500);
WIRE 17 -1 (-6575 4450)(-6575 4550);
WIRE 17 -1 (-6575 4350)(-6575 4450);
WIRE 17 -1 (-6725 4300)(-6725 4400);
WIRE 17 -1 (-6550 2275)(-6550 2375);
WIRE 17 -1 (-6550 2175)(-6550 2275);
WIRE 17 -1 (-6550 2375)(-6550 2475);
WIRE 17 -1 (-6550 2475)(-6550 2575);
WIRE 17 -1 (-6550 2075)(-6550 2175);
WIRE 17 -1 (-6550 1975)(-6550 2075);
WIRE 17 -1 (-6550 2575)(-6550 2675);
WIRE 17 -1 (-6550 2675)(-6550 2775);
WIRE 17 -1 (-6550 1875)(-6550 1975);
WIRE 17 -1 (-6550 1775)(-6550 1875);
WIRE 17 -1 (-6550 2775)(-6550 2875);
WIRE 17 -1 (-6550 2875)(-6550 2975);
WIRE 17 -1 (-6550 1675)(-6550 1775);
WIRE 17 -1 (-6550 1575)(-6550 1675);
WIRE 17 -1 (-6550 2975)(-6550 3175);
WIRE 17 -1 (-6550 3175)(-7650 3175);
WIRE 17 -1 (-6550 1475)(-6550 1575);
WIRE 17 -1 (-6700 2125)(-6700 2225);
WIRE 17 -1 (-6700 2025)(-6700 2125);
WIRE 17 -1 (-6700 2225)(-6700 2325);
WIRE 17 -1 (-6700 2325)(-6700 2425);
WIRE 17 -1 (-6700 1925)(-6700 2025);
WIRE 17 -1 (-6700 1825)(-6700 1925);
WIRE 17 -1 (-6700 2425)(-6700 2525);
WIRE 17 -1 (-6700 2525)(-6700 2625);
WIRE 17 -1 (-6700 1725)(-6700 1825);
WIRE 17 -1 (-6700 1625)(-6700 1725);
WIRE 17 -1 (-6700 2625)(-6700 2725);
WIRE 17 -1 (-6700 2725)(-6700 2825);
WIRE 17 -1 (-6700 1525)(-6700 1625);
WIRE 17 -1 (-6700 1425)(-6700 1525);
WIRE 17 -1 (-6700 2825)(-6700 2925);
WIRE 17 -1 (-6700 2925)(-6700 3125);
WIRE 17 -1 (-6700 3125)(-7650 3125);
WIRE 17 -1 (-3025 1575)(-3025 1475);
WIRE 17 -1 (-3025 1675)(-3025 1575);
WIRE 17 -1 (-3025 1775)(-3025 1675);
WIRE 17 -1 (-3025 1875)(-3025 1775);
WIRE 17 -1 (-3025 1975)(-3025 1875);
WIRE 17 -1 (-3025 2075)(-3025 1975);
WIRE 17 -1 (-3025 2175)(-3025 2075);
WIRE 17 -1 (-3025 2275)(-3025 2175);
WIRE 17 -1 (-3025 2375)(-3025 2275);
WIRE 17 -1 (-3025 2475)(-3025 2375);
WIRE 17 -1 (-3025 2575)(-3025 2475);
WIRE 17 -1 (-3025 2675)(-3025 2575);
WIRE 17 -1 (-3025 2775)(-3025 2675);
WIRE 17 -1 (-3025 2875)(-3025 2775);
WIRE 17 -1 (-3025 2975)(-3025 2875);
WIRE 17 -1 (-3025 3175)(-3025 2975);
WIRE 17 -1 (-3025 3175)(-2000 3175);
FORCEPROP 2 LAST SIG_NAME P5E_CPU0_G3_TX_DP<15:0>
J 0
(-2910 3185);
DISPLAY 0.489362 (-2910 3185);
WIRE 17 -1 (-2875 2025)(-2875 1925);
WIRE 17 -1 (-2875 2125)(-2875 2025);
WIRE 17 -1 (-2875 1925)(-2875 1825);
WIRE 17 -1 (-2875 1825)(-2875 1725);
WIRE 17 -1 (-2875 2225)(-2875 2125);
WIRE 17 -1 (-2875 2325)(-2875 2225);
WIRE 17 -1 (-2875 1725)(-2875 1625);
WIRE 17 -1 (-2875 1625)(-2875 1525);
WIRE 17 -1 (-2875 2425)(-2875 2325);
WIRE 17 -1 (-2875 2525)(-2875 2425);
WIRE 17 -1 (-2875 1525)(-2875 1425);
WIRE 17 -1 (-2875 2625)(-2875 2525);
WIRE 17 -1 (-2875 2725)(-2875 2625);
WIRE 17 -1 (-2875 2825)(-2875 2725);
WIRE 17 -1 (-2875 2925)(-2875 2825);
WIRE 17 -1 (-2875 3125)(-2875 2925);
WIRE 17 -1 (-2875 3125)(-2000 3125);
FORCEPROP 2 LAST SIG_NAME P5E_CPU0_G3_TX_DN<15:0>
J 0
(-2910 3135);
DISPLAY 0.489362 (-2910 3135);
WIRE 17 -1 (-3050 4450)(-3050 4350);
WIRE 17 -1 (-3050 4550)(-3050 4450);
WIRE 17 -1 (-3050 4650)(-3050 4550);
WIRE 17 -1 (-3050 4750)(-3050 4650);
WIRE 17 -1 (-3050 4850)(-3050 4750);
WIRE 17 -1 (-3050 4950)(-3050 4850);
WIRE 17 -1 (-3050 5050)(-3050 4950);
WIRE 17 -1 (-3050 5150)(-3050 5050);
WIRE 17 -1 (-3050 5250)(-3050 5150);
WIRE 17 -1 (-3050 5350)(-3050 5250);
WIRE 17 -1 (-3050 5450)(-3050 5350);
WIRE 17 -1 (-3050 5550)(-3050 5450);
WIRE 17 -1 (-3050 5650)(-3050 5550);
WIRE 17 -1 (-3050 5750)(-3050 5650);
WIRE 17 -1 (-3050 5850)(-3050 5750);
WIRE 17 -1 (-3050 6050)(-3050 5850);
WIRE 17 -1 (-3050 6050)(-1875 6050);
FORCEPROP 2 LAST SIG_NAME GMI_CPU0_G2_CPU1_G0_TX_DP<15:0>
J 0
(-2860 6060);
DISPLAY 0.489362 (-2860 6060);
WIRE 17 -1 (-2900 5100)(-2900 5000);
WIRE 17 -1 (-2900 5200)(-2900 5100);
WIRE 17 -1 (-2900 5000)(-2900 4900);
WIRE 17 -1 (-2900 4900)(-2900 4800);
WIRE 17 -1 (-2900 5300)(-2900 5200);
WIRE 17 -1 (-2900 5400)(-2900 5300);
WIRE 17 -1 (-2900 4800)(-2900 4700);
WIRE 17 -1 (-2900 4700)(-2900 4600);
WIRE 17 -1 (-2900 5500)(-2900 5400);
WIRE 17 -1 (-2900 5600)(-2900 5500);
WIRE 17 -1 (-2900 4600)(-2900 4500);
WIRE 17 -1 (-2900 4500)(-2900 4400);
WIRE 17 -1 (-2900 5700)(-2900 5600);
WIRE 17 -1 (-2900 5800)(-2900 5700);
WIRE 17 -1 (-2900 4400)(-2900 4300);
WIRE 17 -1 (-2900 6000)(-2900 5800);
WIRE 17 -1 (-2900 6000)(-1875 6000);
FORCEPROP 2 LAST SIG_NAME GMI_CPU0_G2_CPU1_G0_TX_DN<15:0>
J 0
(-2860 6010);
DISPLAY 0.489362 (-2860 6010);
WIRE 16 -1 (-3500 2600)(-2975 2600);
WIRE 16 -1 (-3500 2450)(-3125 2450);
WIRE 16 -1 (-3500 2300)(-2975 2300);
WIRE 16 -1 (-3500 1900)(-2975 1900);
WIRE 16 -1 (-3500 1950)(-3125 1950);
WIRE 16 -1 (-6450 2150)(-6000 2150);
WIRE 16 -1 (-3500 2650)(-3125 2650);
WIRE 16 -1 (-3500 2200)(-2975 2200);
WIRE 16 -1 (-3500 2400)(-2975 2400);
WIRE 16 -1 (-3500 2350)(-3125 2350);
WIRE 16 -1 (-3500 2500)(-2975 2500);
WIRE 16 -1 (-3500 2550)(-3125 2550);
WIRE 16 -1 (-3500 2700)(-2975 2700);
WIRE 16 -1 (-3500 2750)(-3125 2750);
WIRE 16 -1 (-3500 2800)(-2975 2800);
WIRE 16 -1 (-3500 2900)(-2975 2900);
WIRE 16 -1 (-3500 2250)(-3125 2250);
WIRE 16 -1 (-3500 2050)(-3125 2050);
WIRE 16 -1 (-3525 4275)(-3000 4275);
WIRE 16 -1 (-6625 4775)(-6025 4775);
WIRE 16 -1 (-6475 4825)(-6025 4825);
WIRE 16 -1 (-3500 2950)(-3125 2950);
WIRE 16 -1 (-3500 2850)(-3125 2850);
WIRE 16 -1 (-6450 2450)(-6000 2450);
WIRE 16 -1 (-6600 2500)(-6000 2500);
WIRE 16 -1 (-6450 2550)(-6000 2550);
WIRE 16 -1 (-6600 2400)(-6000 2400);
WIRE 16 -1 (-6450 2950)(-6000 2950);
WIRE 16 -1 (-6600 2300)(-6000 2300);
WIRE 16 -1 (-6450 2350)(-6000 2350);
WIRE 16 -1 (-6600 2600)(-6000 2600);
WIRE 16 -1 (-6450 2650)(-6000 2650);
WIRE 16 -1 (-6600 2700)(-6000 2700);
WIRE 16 -1 (-6450 2750)(-6000 2750);
WIRE 16 -1 (-6600 2800)(-6000 2800);
WIRE 16 -1 (-6450 2850)(-6000 2850);
WIRE 16 -1 (-6600 2900)(-6000 2900);
WIRE 16 -1 (-6600 2100)(-6000 2100);
WIRE 16 -1 (-6600 2000)(-6000 2000);
WIRE 16 -1 (-6600 1800)(-6000 1800);
WIRE 16 -1 (-3525 4975)(-3000 4975);
WIRE 16 -1 (-3525 4775)(-3000 4775);
WIRE 16 -1 (-3525 4575)(-3000 4575);
WIRE 16 -1 (-3525 4375)(-3000 4375);
WIRE 16 -1 (-3525 4875)(-3000 4875);
WIRE 16 -1 (-3525 4675)(-3000 4675);
WIRE 16 -1 (-3525 4475)(-3000 4475);
WIRE 16 -1 (-3525 5775)(-3000 5775);
WIRE 16 -1 (-3525 5675)(-3000 5675);
WIRE 16 -1 (-3525 5575)(-3000 5575);
WIRE 16 -1 (-3525 5475)(-3000 5475);
WIRE 16 -1 (-3525 5375)(-3000 5375);
WIRE 16 -1 (-3525 5275)(-3000 5275);
WIRE 16 -1 (-3525 5175)(-3000 5175);
WIRE 16 -1 (-3525 5075)(-3000 5075);
WIRE 16 -1 (-3525 5725)(-3150 5725);
WIRE 16 -1 (-3525 5825)(-3150 5825);
WIRE 16 -1 (-3525 5625)(-3150 5625);
WIRE 16 -1 (-3525 5525)(-3150 5525);
WIRE 16 -1 (-3525 5425)(-3150 5425);
WIRE 16 -1 (-3525 5325)(-3150 5325);
WIRE 16 -1 (-3525 5225)(-3150 5225);
WIRE 16 -1 (-3525 5125)(-3150 5125);
WIRE 16 -1 (-3525 5025)(-3150 5025);
WIRE 16 -1 (-3525 4825)(-3150 4825);
WIRE 16 -1 (-3525 4625)(-3150 4625);
WIRE 16 -1 (-3525 4925)(-3150 4925);
WIRE 16 -1 (-3525 4725)(-3150 4725);
WIRE 16 -1 (-3150 4425)(-3525 4425);
WIRE 16 -1 (-3525 4525)(-3150 4525);
WIRE 16 -1 (-3525 4325)(-3150 4325);
WIRE 16 -1 (-3500 2100)(-2975 2100);
WIRE 16 -1 (-3500 2150)(-3125 2150);
WIRE 16 -1 (-3500 1500)(-2975 1500);
WIRE 16 -1 (-3500 1800)(-2975 1800);
WIRE 16 -1 (-3500 1400)(-2975 1400);
WIRE 16 -1 (-3500 1700)(-2975 1700);
WIRE 16 -1 (-3500 1600)(-2975 1600);
WIRE 16 -1 (-3500 2000)(-2975 2000);
WIRE 16 -1 (-3500 1650)(-3125 1650);
WIRE 16 -1 (-3500 1850)(-3125 1850);
WIRE 16 -1 (-3500 1550)(-3125 1550);
WIRE 16 -1 (-3500 1750)(-3125 1750);
WIRE 16 -1 (-3500 1450)(-3125 1450);
WIRE 16 -1 (-6475 4425)(-6025 4425);
WIRE 16 -1 (-6625 4375)(-6025 4375);
WIRE 16 -1 (-6625 4475)(-6025 4475);
WIRE 16 -1 (-6475 4325)(-6025 4325);
WIRE 16 -1 (-6625 4275)(-6025 4275);
WIRE 16 -1 (-6475 5825)(-6025 5825);
WIRE 16 -1 (-6475 5725)(-6025 5725);
WIRE 16 -1 (-6475 5625)(-6025 5625);
WIRE 16 -1 (-6625 5775)(-6025 5775);
WIRE 16 -1 (-6475 5525)(-6025 5525);
WIRE 16 -1 (-6625 5675)(-6025 5675);
WIRE 16 -1 (-6475 5425)(-6025 5425);
WIRE 16 -1 (-6625 5575)(-6025 5575);
WIRE 16 -1 (-6475 5325)(-6025 5325);
WIRE 16 -1 (-6625 5475)(-6025 5475);
WIRE 16 -1 (-6625 5375)(-6025 5375);
WIRE 16 -1 (-6450 1850)(-6000 1850);
WIRE 16 -1 (-6600 1900)(-6000 1900);
WIRE 16 -1 (-6450 1950)(-6000 1950);
WIRE 16 -1 (-6600 1400)(-6000 1400);
WIRE 16 -1 (-6450 1450)(-6000 1450);
WIRE 16 -1 (-6600 1500)(-6000 1500);
WIRE 16 -1 (-6450 1550)(-6000 1550);
WIRE 16 -1 (-6600 1600)(-6000 1600);
WIRE 16 -1 (-6600 1700)(-6000 1700);
WIRE 16 -1 (-6450 1650)(-6000 1650);
WIRE 16 -1 (-6450 1750)(-6000 1750);
WIRE 16 -1 (-6450 2050)(-6000 2050);
WIRE 16 -1 (-6600 2200)(-6000 2200);
WIRE 16 -1 (-6450 2250)(-6000 2250);
WIRE 16 -1 (-6475 4525)(-6025 4525);
WIRE 16 -1 (-6625 4575)(-6025 4575);
WIRE 16 -1 (-6475 4625)(-6025 4625);
WIRE 16 -1 (-6625 4675)(-6025 4675);
WIRE 16 -1 (-6475 4725)(-6025 4725);
WIRE 16 -1 (-6625 4875)(-6025 4875);
WIRE 16 -1 (-6475 4925)(-6025 4925);
WIRE 16 -1 (-6625 4975)(-6025 4975);
WIRE 16 -1 (-6475 5025)(-6025 5025);
WIRE 16 -1 (-6625 5075)(-6025 5075);
WIRE 16 -1 (-6475 5125)(-6025 5125);
WIRE 16 -1 (-6625 5175)(-6025 5175);
WIRE 16 -1 (-6475 5225)(-6025 5225);
WIRE 16 -1 (-6625 5275)(-6025 5275);
FORCENOTE
CPU0 G3[15:0] TO OCP SLOT#0
(-2550 2325) 0;
DISPLAY LEFT (-2550 2325);
DISPLAY 1.595745 (-2550 2325);
QUIT
